FILE_TYPE = MACRO_DRAWING;
SET COLOR_WIRE YELLOW;
SET COLOR_PROP MONO;
SET COLOR_DOT WHITE;
SET COLOR_ARC YELLOW;
SET COLOR_BODY GREEN;
SET COLOR_NOTE MONO;
SET PROP_DISPLAY VALUE;
SET PAGE_NUMBER P75;
FORCEADD GND..1
(-5675 400);
FORCEPROP 3 LASTPIN (-5675 450) SIG_NAME GND\g
J 0
(-5665 460);
DISPLAY 0.659574 (-5665 460);
PAINT MONO (-5665 460);
DISPLAY INVISIBLE (-5665 460);
FORCEPROP 1 LAST VOLTAGE 0.0V
J 0
(-5720 357);
DISPLAY 0.340426 (-5720 357);
PAINT SKYBLUE (-5720 357);
DISPLAY INVISIBLE (-5720 357);
FORCEPROP 2 LAST CDS_LIB mstr_symbols
J 0
(-5675 400);
PAINT ORANGE (-5675 400);
DISPLAY INVISIBLE (-5675 400);
FORCEPROP 1 LAST SIZE 1B
J 0
(-5600 350);
DISPLAY 1.170213 (-5600 350);
PAINT AQUA (-5600 350);
DISPLAY INVISIBLE (-5600 350);
FORCEPROP 1 LAST BODY_TYPE PLUMBING
J 0
(-5720 357);
DISPLAY 0.340426 (-5720 357);
PAINT GREEN (-5720 357);
DISPLAY INVISIBLE (-5720 357);
FORCEPROP 1 LAST PATH I10
J 0
(-5600 400);
DISPLAY 0.872340 (-5600 400);
PAINT AQUA (-5600 400);
DISPLAY INVISIBLE (-5600 400);
FORCEPROP 1 LAST HDL_POWER GND
J 0
(-5675 550);
DISPLAY 1.170213 (-5675 550);
PAINT GREEN (-5675 550);
DISPLAY INVISIBLE (-5675 550);
FORCEADD GND..1
(-3775 400);
FORCEPROP 3 LASTPIN (-3775 450) SIG_NAME GND\g
J 0
(-3765 460);
DISPLAY 0.659574 (-3765 460);
PAINT MONO (-3765 460);
DISPLAY INVISIBLE (-3765 460);
FORCEPROP 1 LAST VOLTAGE 0.0V
J 0
(-3820 357);
DISPLAY 0.340426 (-3820 357);
PAINT SKYBLUE (-3820 357);
DISPLAY INVISIBLE (-3820 357);
FORCEPROP 1 LAST SIZE 1B
J 0
(-3700 350);
DISPLAY 1.170213 (-3700 350);
PAINT AQUA (-3700 350);
DISPLAY INVISIBLE (-3700 350);
FORCEPROP 2 LAST CDS_LIB mstr_symbols
J 0
(-3775 400);
PAINT ORANGE (-3775 400);
DISPLAY INVISIBLE (-3775 400);
FORCEPROP 1 LAST BODY_TYPE PLUMBING
J 0
(-3820 357);
DISPLAY 0.340426 (-3820 357);
PAINT GREEN (-3820 357);
DISPLAY INVISIBLE (-3820 357);
FORCEPROP 1 LAST PATH I11
J 0
(-3700 400);
DISPLAY 0.872340 (-3700 400);
PAINT AQUA (-3700 400);
DISPLAY INVISIBLE (-3700 400);
FORCEPROP 1 LAST HDL_POWER GND
J 0
(-3775 550);
DISPLAY 1.170213 (-3775 550);
PAINT GREEN (-3775 550);
DISPLAY INVISIBLE (-3775 550);
FORCEADD GND..1
(-1975 400);
FORCEPROP 3 LASTPIN (-1975 450) SIG_NAME GND\g
J 0
(-1965 460);
DISPLAY 0.659574 (-1965 460);
PAINT MONO (-1965 460);
DISPLAY INVISIBLE (-1965 460);
FORCEPROP 1 LAST VOLTAGE 0.0V
J 0
(-2020 357);
DISPLAY 0.340426 (-2020 357);
PAINT SKYBLUE (-2020 357);
DISPLAY INVISIBLE (-2020 357);
FORCEPROP 1 LAST SIZE 1B
J 0
(-1900 350);
DISPLAY 1.170213 (-1900 350);
PAINT AQUA (-1900 350);
DISPLAY INVISIBLE (-1900 350);
FORCEPROP 2 LAST CDS_LIB mstr_symbols
J 0
(-1975 400);
PAINT ORANGE (-1975 400);
DISPLAY INVISIBLE (-1975 400);
FORCEPROP 1 LAST BODY_TYPE PLUMBING
J 0
(-2020 357);
DISPLAY 0.340426 (-2020 357);
PAINT GREEN (-2020 357);
DISPLAY INVISIBLE (-2020 357);
FORCEPROP 1 LAST PATH I12
J 0
(-1900 400);
DISPLAY 0.872340 (-1900 400);
PAINT AQUA (-1900 400);
DISPLAY INVISIBLE (-1900 400);
FORCEPROP 1 LAST HDL_POWER GND
J 0
(-1975 550);
DISPLAY 1.170213 (-1975 550);
PAINT GREEN (-1975 550);
DISPLAY INVISIBLE (-1975 550);
FORCEADD GND..1
(-2275 400);
FORCEPROP 3 LASTPIN (-2275 450) SIG_NAME GND\g
J 0
(-2265 460);
DISPLAY 0.659574 (-2265 460);
PAINT MONO (-2265 460);
DISPLAY INVISIBLE (-2265 460);
FORCEPROP 1 LAST VOLTAGE 0.0V
J 0
(-2320 357);
DISPLAY 0.340426 (-2320 357);
PAINT SKYBLUE (-2320 357);
DISPLAY INVISIBLE (-2320 357);
FORCEPROP 2 LAST CDS_LIB mstr_symbols
J 0
(-2275 400);
PAINT ORANGE (-2275 400);
DISPLAY INVISIBLE (-2275 400);
FORCEPROP 1 LAST SIZE 1B
J 0
(-2200 350);
DISPLAY 1.170213 (-2200 350);
PAINT AQUA (-2200 350);
DISPLAY INVISIBLE (-2200 350);
FORCEPROP 1 LAST BODY_TYPE PLUMBING
J 0
(-2320 357);
DISPLAY 0.340426 (-2320 357);
PAINT GREEN (-2320 357);
DISPLAY INVISIBLE (-2320 357);
FORCEPROP 1 LAST PATH I13
J 0
(-2200 400);
DISPLAY 0.872340 (-2200 400);
PAINT AQUA (-2200 400);
DISPLAY INVISIBLE (-2200 400);
FORCEPROP 1 LAST HDL_POWER GND
J 0
(-2275 550);
DISPLAY 1.170213 (-2275 550);
PAINT GREEN (-2275 550);
DISPLAY INVISIBLE (-2275 550);
FORCEADD GND..1
(-4150 400);
FORCEPROP 3 LASTPIN (-4150 450) SIG_NAME GND\g
J 0
(-4140 460);
DISPLAY 0.659574 (-4140 460);
PAINT MONO (-4140 460);
DISPLAY INVISIBLE (-4140 460);
FORCEPROP 1 LAST VOLTAGE 0.0V
J 0
(-4195 357);
DISPLAY 0.340426 (-4195 357);
PAINT SKYBLUE (-4195 357);
DISPLAY INVISIBLE (-4195 357);
FORCEPROP 2 LAST CDS_LIB mstr_symbols
J 0
(-4150 400);
PAINT ORANGE (-4150 400);
DISPLAY INVISIBLE (-4150 400);
FORCEPROP 1 LAST SIZE 1B
J 0
(-4075 350);
DISPLAY 1.170213 (-4075 350);
PAINT AQUA (-4075 350);
DISPLAY INVISIBLE (-4075 350);
FORCEPROP 1 LAST BODY_TYPE PLUMBING
J 0
(-4195 357);
DISPLAY 0.340426 (-4195 357);
PAINT GREEN (-4195 357);
DISPLAY INVISIBLE (-4195 357);
FORCEPROP 1 LAST PATH I14
J 0
(-4075 400);
DISPLAY 0.872340 (-4075 400);
PAINT AQUA (-4075 400);
DISPLAY INVISIBLE (-4075 400);
FORCEPROP 1 LAST HDL_POWER GND
J 0
(-4150 550);
DISPLAY 1.170213 (-4150 550);
PAINT GREEN (-4150 550);
DISPLAY INVISIBLE (-4150 550);
FORCEADD GND..1
(-5950 400);
FORCEPROP 3 LASTPIN (-5950 450) SIG_NAME GND\g
J 0
(-5940 460);
DISPLAY 0.659574 (-5940 460);
PAINT MONO (-5940 460);
DISPLAY INVISIBLE (-5940 460);
FORCEPROP 1 LAST VOLTAGE 0.0V
J 0
(-5995 357);
DISPLAY 0.340426 (-5995 357);
PAINT SKYBLUE (-5995 357);
DISPLAY INVISIBLE (-5995 357);
FORCEPROP 2 LAST CDS_LIB mstr_symbols
J 0
(-5950 400);
PAINT ORANGE (-5950 400);
DISPLAY INVISIBLE (-5950 400);
FORCEPROP 1 LAST SIZE 1B
J 0
(-5875 350);
DISPLAY 1.170213 (-5875 350);
PAINT AQUA (-5875 350);
DISPLAY INVISIBLE (-5875 350);
FORCEPROP 1 LAST BODY_TYPE PLUMBING
J 0
(-5995 357);
DISPLAY 0.340426 (-5995 357);
PAINT GREEN (-5995 357);
DISPLAY INVISIBLE (-5995 357);
FORCEPROP 1 LAST PATH I15
J 0
(-5875 400);
DISPLAY 0.872340 (-5875 400);
PAINT AQUA (-5875 400);
DISPLAY INVISIBLE (-5875 400);
FORCEPROP 1 LAST HDL_POWER GND
J 0
(-5950 550);
DISPLAY 1.170213 (-5950 550);
PAINT GREEN (-5950 550);
DISPLAY INVISIBLE (-5950 550);
FORCEADD GND..1
(-450 1700);
FORCEPROP 3 LASTPIN (-450 1750) SIG_NAME GND\g
J 0
(-440 1760);
DISPLAY 0.659574 (-440 1760);
PAINT MONO (-440 1760);
DISPLAY INVISIBLE (-440 1760);
FORCEPROP 1 LAST VOLTAGE 0.0V
J 0
(-495 1657);
DISPLAY 0.340426 (-495 1657);
PAINT SKYBLUE (-495 1657);
DISPLAY INVISIBLE (-495 1657);
FORCEPROP 2 LAST CDS_LIB mstr_symbols
J 0
(-450 1700);
PAINT ORANGE (-450 1700);
DISPLAY INVISIBLE (-450 1700);
FORCEPROP 1 LAST SIZE 1B
J 0
(-375 1650);
DISPLAY 1.170213 (-375 1650);
PAINT AQUA (-375 1650);
DISPLAY INVISIBLE (-375 1650);
FORCEPROP 1 LAST BODY_TYPE PLUMBING
J 0
(-495 1657);
DISPLAY 0.340426 (-495 1657);
PAINT GREEN (-495 1657);
DISPLAY INVISIBLE (-495 1657);
FORCEPROP 1 LAST PATH I16
J 0
(-375 1700);
DISPLAY 0.872340 (-375 1700);
PAINT AQUA (-375 1700);
DISPLAY INVISIBLE (-375 1700);
FORCEPROP 1 LAST HDL_POWER GND
J 0
(-450 1850);
DISPLAY 1.170213 (-450 1850);
PAINT GREEN (-450 1850);
DISPLAY INVISIBLE (-450 1850);
FORCEADD SKX_EXT_B..27
(-6725 2525);
FORCEPROP 1 LAST LOCATION U2D1
J 0
(-7275 4775);
DISPLAY 0.617021 (-7275 4775);
PAINT AQUA (-7275 4775);
FORCEPROP 1 LAST PART_NUMBER TBD
J 0
(-7275 375);
DISPLAY 0.617021 (-7275 375);
PAINT BLUE (-7275 375);
FORCEPROP 1 LAST MATERIAL IC
J 0
(-7275 4725);
DISPLAY 0.617021 (-7275 4725);
PAINT SKYBLUE (-7275 4725);
FORCEPROP 2 LASTPIN (-7325 4375) $PN BG80
J 2
(-7335 4385);
DISPLAY 0.617021 (-7335 4385);
PAINT ORANGE (-7335 4385);
FORCEPROP 2 LASTPIN (-7325 4275) $PN BH7
J 2
(-7335 4285);
DISPLAY 0.617021 (-7335 4285);
PAINT ORANGE (-7335 4285);
FORCEPROP 2 LASTPIN (-7325 4175) $PN BH11
J 2
(-7335 4185);
DISPLAY 0.617021 (-7335 4185);
PAINT ORANGE (-7335 4185);
FORCEPROP 2 LASTPIN (-7325 4125) $PN BH15
J 2
(-7335 4135);
DISPLAY 0.617021 (-7335 4135);
PAINT ORANGE (-7335 4135);
FORCEPROP 2 LASTPIN (-7325 4075) $PN BH21
J 2
(-7335 4085);
DISPLAY 0.617021 (-7335 4085);
PAINT ORANGE (-7335 4085);
FORCEPROP 2 LASTPIN (-7325 4025) $PN BJ4
J 2
(-7335 4035);
DISPLAY 0.617021 (-7335 4035);
PAINT ORANGE (-7335 4035);
FORCEPROP 2 LASTPIN (-7325 3975) $PN BJ6
J 2
(-7335 3985);
DISPLAY 0.617021 (-7335 3985);
PAINT ORANGE (-7335 3985);
FORCEPROP 2 LASTPIN (-7325 3925) $PN BK3
J 2
(-7335 3935);
DISPLAY 0.617021 (-7335 3935);
PAINT ORANGE (-7335 3935);
FORCEPROP 2 LASTPIN (-7325 3875) $PN BK7
J 2
(-7335 3885);
DISPLAY 0.617021 (-7335 3885);
PAINT ORANGE (-7335 3885);
FORCEPROP 2 LASTPIN (-7325 3825) $PN BK11
J 2
(-7335 3835);
DISPLAY 0.617021 (-7335 3835);
PAINT ORANGE (-7335 3835);
FORCEPROP 2 LASTPIN (-7325 3775) $PN BK19
J 2
(-7335 3785);
DISPLAY 0.617021 (-7335 3785);
PAINT ORANGE (-7335 3785);
FORCEPROP 2 LASTPIN (-7325 3725) $PN BL6
J 2
(-7335 3735);
DISPLAY 0.617021 (-7335 3735);
PAINT ORANGE (-7335 3735);
FORCEPROP 2 LASTPIN (-7325 3675) $PN BL10
J 2
(-7335 3685);
DISPLAY 0.617021 (-7335 3685);
PAINT ORANGE (-7335 3685);
FORCEPROP 2 LASTPIN (-7325 3625) $PN BL12
J 2
(-7335 3635);
DISPLAY 0.617021 (-7335 3635);
PAINT ORANGE (-7335 3635);
FORCEPROP 2 LASTPIN (-7325 3575) $PN P61
J 2
(-7335 3585);
DISPLAY 0.617021 (-7335 3585);
PAINT ORANGE (-7335 3585);
FORCEPROP 2 LASTPIN (-7325 3525) $PN BL22
J 2
(-7335 3535);
DISPLAY 0.617021 (-7335 3535);
PAINT ORANGE (-7335 3535);
FORCEPROP 2 LASTPIN (-7325 3475) $PN BL24
J 2
(-7335 3485);
DISPLAY 0.617021 (-7335 3485);
PAINT ORANGE (-7335 3485);
FORCEPROP 2 LASTPIN (-7325 3425) $PN BL64
J 2
(-7335 3435);
DISPLAY 0.617021 (-7335 3435);
PAINT ORANGE (-7335 3435);
FORCEPROP 2 LASTPIN (-7325 3375) $PN BL66
J 2
(-7335 3385);
DISPLAY 0.617021 (-7335 3385);
PAINT ORANGE (-7335 3385);
FORCEPROP 2 LASTPIN (-7325 3325) $PN BL68
J 2
(-7335 3335);
DISPLAY 0.617021 (-7335 3335);
PAINT ORANGE (-7335 3335);
FORCEPROP 2 LASTPIN (-7325 3275) $PN BL70
J 2
(-7335 3285);
DISPLAY 0.617021 (-7335 3285);
PAINT ORANGE (-7335 3285);
FORCEPROP 2 LASTPIN (-7325 3225) $PN BL72
J 2
(-7335 3235);
DISPLAY 0.617021 (-7335 3235);
PAINT ORANGE (-7335 3235);
FORCEPROP 2 LASTPIN (-7325 3175) $PN BL74
J 2
(-7335 3185);
DISPLAY 0.617021 (-7335 3185);
PAINT ORANGE (-7335 3185);
FORCEPROP 2 LASTPIN (-7325 3125) $PN BL76
J 2
(-7335 3135);
DISPLAY 0.617021 (-7335 3135);
PAINT ORANGE (-7335 3135);
FORCEPROP 2 LASTPIN (-7325 3075) $PN BL78
J 2
(-7335 3085);
DISPLAY 0.617021 (-7335 3085);
PAINT ORANGE (-7335 3085);
FORCEPROP 2 LASTPIN (-7325 3025) $PN BL80
J 2
(-7335 3035);
DISPLAY 0.617021 (-7335 3035);
PAINT ORANGE (-7335 3035);
FORCEPROP 2 LASTPIN (-7325 2975) $PN BL82
J 2
(-7335 2985);
DISPLAY 0.617021 (-7335 2985);
PAINT ORANGE (-7335 2985);
FORCEPROP 2 LASTPIN (-7325 2925) $PN BM9
J 2
(-7335 2935);
DISPLAY 0.617021 (-7335 2935);
PAINT ORANGE (-7335 2935);
FORCEPROP 2 LASTPIN (-7325 2875) $PN BM13
J 2
(-7335 2885);
DISPLAY 0.617021 (-7335 2885);
PAINT ORANGE (-7335 2885);
FORCEPROP 2 LASTPIN (-7325 2825) $PN BM15
J 2
(-7335 2835);
DISPLAY 0.617021 (-7335 2835);
PAINT ORANGE (-7335 2835);
FORCEPROP 2 LASTPIN (-7325 2775) $PN P59
J 2
(-7335 2785);
DISPLAY 0.617021 (-7335 2785);
PAINT ORANGE (-7335 2785);
FORCEPROP 2 LASTPIN (-7325 2725) $PN BM25
J 2
(-7335 2735);
DISPLAY 0.617021 (-7335 2735);
PAINT ORANGE (-7335 2735);
FORCEPROP 2 LASTPIN (-7325 2675) $PN BN6
J 2
(-7335 2685);
DISPLAY 0.617021 (-7335 2685);
PAINT ORANGE (-7335 2685);
FORCEPROP 2 LASTPIN (-7325 2625) $PN BN10
J 2
(-7335 2635);
DISPLAY 0.617021 (-7335 2635);
PAINT ORANGE (-7335 2635);
FORCEPROP 2 LASTPIN (-7325 2575) $PN BN20
J 2
(-7335 2585);
DISPLAY 0.617021 (-7335 2585);
PAINT ORANGE (-7335 2585);
FORCEPROP 2 LASTPIN (-7325 2525) $PN BN26
J 2
(-7335 2535);
DISPLAY 0.617021 (-7335 2535);
PAINT ORANGE (-7335 2535);
FORCEPROP 2 LASTPIN (-7325 2475) $PN BP3
J 2
(-7335 2485);
DISPLAY 0.617021 (-7335 2485);
PAINT ORANGE (-7335 2485);
FORCEPROP 2 LASTPIN (-7325 2425) $PN BP27
J 2
(-7335 2435);
DISPLAY 0.617021 (-7335 2435);
PAINT ORANGE (-7335 2435);
FORCEPROP 2 LASTPIN (-7325 2375) $PN BR6
J 2
(-7335 2385);
DISPLAY 0.617021 (-7335 2385);
PAINT ORANGE (-7335 2385);
FORCEPROP 2 LASTPIN (-7325 2325) $PN BR10
J 2
(-7335 2335);
DISPLAY 0.617021 (-7335 2335);
PAINT ORANGE (-7335 2335);
FORCEPROP 2 LASTPIN (-7325 2275) $PN BR16
J 2
(-7335 2285);
DISPLAY 0.617021 (-7335 2285);
PAINT ORANGE (-7335 2285);
FORCEPROP 2 LASTPIN (-7325 2225) $PN P57
J 2
(-7335 2235);
DISPLAY 0.617021 (-7335 2235);
PAINT ORANGE (-7335 2235);
FORCEPROP 2 LASTPIN (-7325 2175) $PN BR64
J 2
(-7335 2185);
DISPLAY 0.617021 (-7335 2185);
PAINT ORANGE (-7335 2185);
FORCEPROP 2 LASTPIN (-7325 2125) $PN BR66
J 2
(-7335 2135);
DISPLAY 0.617021 (-7335 2135);
PAINT ORANGE (-7335 2135);
FORCEPROP 2 LASTPIN (-7325 2075) $PN BR68
J 2
(-7335 2085);
DISPLAY 0.617021 (-7335 2085);
PAINT ORANGE (-7335 2085);
FORCEPROP 2 LASTPIN (-7325 2025) $PN BR70
J 2
(-7335 2035);
DISPLAY 0.617021 (-7335 2035);
PAINT ORANGE (-7335 2035);
FORCEPROP 2 LASTPIN (-7325 1975) $PN BR72
J 2
(-7335 1985);
DISPLAY 0.617021 (-7335 1985);
PAINT ORANGE (-7335 1985);
FORCEPROP 2 LASTPIN (-7325 1925) $PN BR74
J 2
(-7335 1935);
DISPLAY 0.617021 (-7335 1935);
PAINT ORANGE (-7335 1935);
FORCEPROP 2 LASTPIN (-7325 1875) $PN BR76
J 2
(-7335 1885);
DISPLAY 0.617021 (-7335 1885);
PAINT ORANGE (-7335 1885);
FORCEPROP 2 LASTPIN (-7325 1825) $PN BR78
J 2
(-7335 1835);
DISPLAY 0.617021 (-7335 1835);
PAINT ORANGE (-7335 1835);
FORCEPROP 2 LASTPIN (-7325 1775) $PN BR80
J 2
(-7335 1785);
DISPLAY 0.617021 (-7335 1785);
PAINT ORANGE (-7335 1785);
FORCEPROP 2 LASTPIN (-7325 1725) $PN BR82
J 2
(-7335 1735);
DISPLAY 0.617021 (-7335 1735);
PAINT ORANGE (-7335 1735);
FORCEPROP 2 LASTPIN (-7325 1675) $PN BT3
J 2
(-7335 1685);
DISPLAY 0.617021 (-7335 1685);
PAINT ORANGE (-7335 1685);
FORCEPROP 2 LASTPIN (-7325 1625) $PN BT5
J 2
(-7335 1635);
DISPLAY 0.617021 (-7335 1635);
PAINT ORANGE (-7335 1635);
FORCEPROP 2 LASTPIN (-7325 1575) $PN BT21
J 2
(-7335 1585);
DISPLAY 0.617021 (-7335 1585);
PAINT ORANGE (-7335 1585);
FORCEPROP 2 LASTPIN (-7325 1525) $PN BT23
J 2
(-7335 1535);
DISPLAY 0.617021 (-7335 1535);
PAINT ORANGE (-7335 1535);
FORCEPROP 2 LASTPIN (-7325 1475) $PN BT25
J 2
(-7335 1485);
DISPLAY 0.617021 (-7335 1485);
PAINT ORANGE (-7335 1485);
FORCEPROP 2 LASTPIN (-7325 1425) $PN BU8
J 2
(-7335 1435);
DISPLAY 0.617021 (-7335 1435);
PAINT ORANGE (-7335 1435);
FORCEPROP 2 LASTPIN (-7325 1375) $PN BV5
J 2
(-7335 1385);
DISPLAY 0.617021 (-7335 1385);
PAINT ORANGE (-7335 1385);
FORCEPROP 2 LASTPIN (-7325 1325) $PN BU10
J 2
(-7335 1335);
DISPLAY 0.617021 (-7335 1335);
PAINT ORANGE (-7335 1335);
FORCEPROP 2 LASTPIN (-7325 1275) $PN BV17
J 2
(-7335 1285);
DISPLAY 0.617021 (-7335 1285);
PAINT ORANGE (-7335 1285);
FORCEPROP 2 LASTPIN (-7325 1225) $PN BV25
J 2
(-7335 1235);
DISPLAY 0.617021 (-7335 1235);
PAINT ORANGE (-7335 1235);
FORCEPROP 2 LASTPIN (-7325 1175) $PN BW6
J 2
(-7335 1185);
DISPLAY 0.617021 (-7335 1185);
PAINT ORANGE (-7335 1185);
FORCEPROP 2 LASTPIN (-7325 1125) $PN P55
J 2
(-7335 1135);
DISPLAY 0.617021 (-7335 1135);
PAINT ORANGE (-7335 1135);
FORCEPROP 2 LASTPIN (-7325 1075) $PN BW12
J 2
(-7335 1085);
DISPLAY 0.617021 (-7335 1085);
PAINT ORANGE (-7335 1085);
FORCEPROP 2 LASTPIN (-7325 1025) $PN BW14
J 2
(-7335 1035);
DISPLAY 0.617021 (-7335 1035);
PAINT ORANGE (-7335 1035);
FORCEPROP 2 LASTPIN (-7325 975) $PN BW16
J 2
(-7335 985);
DISPLAY 0.617021 (-7335 985);
PAINT ORANGE (-7335 985);
FORCEPROP 2 LASTPIN (-7325 925) $PN BW18
J 2
(-7335 935);
DISPLAY 0.617021 (-7335 935);
PAINT ORANGE (-7335 935);
FORCEPROP 2 LASTPIN (-7325 875) $PN BW26
J 2
(-7335 885);
DISPLAY 0.617021 (-7335 885);
PAINT ORANGE (-7335 885);
FORCEPROP 2 LASTPIN (-7325 825) $PN BW72
J 2
(-7335 835);
DISPLAY 0.617021 (-7335 835);
PAINT ORANGE (-7335 835);
FORCEPROP 2 LASTPIN (-7325 775) $PN BW74
J 2
(-7335 785);
DISPLAY 0.617021 (-7335 785);
PAINT ORANGE (-7335 785);
FORCEPROP 2 LASTPIN (-7325 725) $PN BW76
J 2
(-7335 735);
DISPLAY 0.617021 (-7335 735);
PAINT ORANGE (-7335 735);
FORCEPROP 2 LASTPIN (-7325 675) $PN BW78
J 2
(-7335 685);
DISPLAY 0.617021 (-7335 685);
PAINT ORANGE (-7335 685);
FORCEPROP 2 LASTPIN (-7325 625) $PN BW80
J 2
(-7335 635);
DISPLAY 0.617021 (-7335 635);
PAINT ORANGE (-7335 635);
FORCEPROP 2 LASTPIN (-7325 575) $PN BW82
J 2
(-7335 585);
DISPLAY 0.617021 (-7335 585);
PAINT ORANGE (-7335 585);
FORCEPROP 2 LASTPIN (-6125 4525) $PN BY11
J 0
(-6115 4535);
DISPLAY 0.617021 (-6115 4535);
PAINT ORANGE (-6115 4535);
FORCEPROP 2 LASTPIN (-6125 4475) $PN BY13
J 0
(-6115 4485);
DISPLAY 0.617021 (-6115 4485);
PAINT ORANGE (-6115 4485);
FORCEPROP 2 LASTPIN (-6125 4425) $PN BY23
J 0
(-6115 4435);
DISPLAY 0.617021 (-6115 4435);
PAINT ORANGE (-6115 4435);
FORCEPROP 2 LASTPIN (-6125 4375) $PN BY63
J 0
(-6115 4385);
DISPLAY 0.617021 (-6115 4385);
PAINT ORANGE (-6115 4385);
FORCEPROP 2 LASTPIN (-6125 4325) $PN BY65
J 0
(-6115 4335);
DISPLAY 0.617021 (-6115 4335);
PAINT ORANGE (-6115 4335);
FORCEPROP 2 LASTPIN (-6125 4275) $PN BY67
J 0
(-6115 4285);
DISPLAY 0.617021 (-6115 4285);
PAINT ORANGE (-6115 4285);
FORCEPROP 2 LASTPIN (-6125 4225) $PN BY69
J 0
(-6115 4235);
DISPLAY 0.617021 (-6115 4235);
PAINT ORANGE (-6115 4235);
FORCEPROP 2 LASTPIN (-6125 4175) $PN BY71
J 0
(-6115 4185);
DISPLAY 0.617021 (-6115 4185);
PAINT ORANGE (-6115 4185);
FORCEPROP 2 LASTPIN (-6125 4125) $PN CA2
J 0
(-6115 4135);
DISPLAY 0.617021 (-6115 4135);
PAINT ORANGE (-6115 4135);
FORCEPROP 2 LASTPIN (-6125 4075) $PN CA6
J 0
(-6115 4085);
DISPLAY 0.617021 (-6115 4085);
PAINT ORANGE (-6115 4085);
FORCEPROP 2 LASTPIN (-6125 4025) $PN CA8
J 0
(-6115 4035);
DISPLAY 0.617021 (-6115 4035);
PAINT ORANGE (-6115 4035);
FORCEPROP 2 LASTPIN (-6125 3975) $PN CA10
J 0
(-6115 3985);
DISPLAY 0.617021 (-6115 3985);
PAINT ORANGE (-6115 3985);
FORCEPROP 2 LASTPIN (-6125 3925) $PN CA14
J 0
(-6115 3935);
DISPLAY 0.617021 (-6115 3935);
PAINT ORANGE (-6115 3935);
FORCEPROP 2 LASTPIN (-6125 3875) $PN CA18
J 0
(-6115 3885);
DISPLAY 0.617021 (-6115 3885);
PAINT ORANGE (-6115 3885);
FORCEPROP 2 LASTPIN (-6125 3825) $PN CA26
J 0
(-6115 3835);
DISPLAY 0.617021 (-6115 3835);
PAINT ORANGE (-6115 3835);
FORCEPROP 2 LASTPIN (-6125 3775) $PN CA64
J 0
(-6115 3785);
DISPLAY 0.617021 (-6115 3785);
PAINT ORANGE (-6115 3785);
FORCEPROP 2 LASTPIN (-6125 3725) $PN CA66
J 0
(-6115 3735);
DISPLAY 0.617021 (-6115 3735);
PAINT ORANGE (-6115 3735);
FORCEPROP 2 LASTPIN (-6125 3675) $PN CA68
J 0
(-6115 3685);
DISPLAY 0.617021 (-6115 3685);
PAINT ORANGE (-6115 3685);
FORCEPROP 2 LASTPIN (-6125 3625) $PN CA70
J 0
(-6115 3635);
DISPLAY 0.617021 (-6115 3635);
PAINT ORANGE (-6115 3635);
FORCEPROP 2 LASTPIN (-6125 3575) $PN CB7
J 0
(-6115 3585);
DISPLAY 0.617021 (-6115 3585);
PAINT ORANGE (-6115 3585);
FORCEPROP 2 LASTPIN (-6125 3525) $PN CB9
J 0
(-6115 3535);
DISPLAY 0.617021 (-6115 3535);
PAINT ORANGE (-6115 3535);
FORCEPROP 2 LASTPIN (-6125 3475) $PN CB27
J 0
(-6115 3485);
DISPLAY 0.617021 (-6115 3485);
PAINT ORANGE (-6115 3485);
FORCEPROP 2 LASTPIN (-6125 3425) $PN CB63
J 0
(-6115 3435);
DISPLAY 0.617021 (-6115 3435);
PAINT ORANGE (-6115 3435);
FORCEPROP 2 LASTPIN (-6125 3375) $PN CB71
J 0
(-6115 3385);
DISPLAY 0.617021 (-6115 3385);
PAINT ORANGE (-6115 3385);
FORCEPROP 2 LASTPIN (-6125 3325) $PN CC4
J 0
(-6115 3335);
DISPLAY 0.617021 (-6115 3335);
PAINT ORANGE (-6115 3335);
FORCEPROP 2 LASTPIN (-6125 3275) $PN CC16
J 0
(-6115 3285);
DISPLAY 0.617021 (-6115 3285);
PAINT ORANGE (-6115 3285);
FORCEPROP 2 LASTPIN (-6125 3225) $PN CC18
J 0
(-6115 3235);
DISPLAY 0.617021 (-6115 3235);
PAINT ORANGE (-6115 3235);
FORCEPROP 2 LASTPIN (-6125 3175) $PN CC24
J 0
(-6115 3185);
DISPLAY 0.617021 (-6115 3185);
PAINT ORANGE (-6115 3185);
FORCEPROP 2 LASTPIN (-6125 3125) $PN CC64
J 0
(-6115 3135);
DISPLAY 0.617021 (-6115 3135);
PAINT ORANGE (-6115 3135);
FORCEPROP 2 LASTPIN (-6125 3075) $PN CC72
J 0
(-6115 3085);
DISPLAY 0.617021 (-6115 3085);
PAINT ORANGE (-6115 3085);
FORCEPROP 2 LASTPIN (-6125 3025) $PN CC74
J 0
(-6115 3035);
DISPLAY 0.617021 (-6115 3035);
PAINT ORANGE (-6115 3035);
FORCEPROP 2 LASTPIN (-6125 2975) $PN CC76
J 0
(-6115 2985);
DISPLAY 0.617021 (-6115 2985);
PAINT ORANGE (-6115 2985);
FORCEPROP 2 LASTPIN (-6125 2925) $PN CC78
J 0
(-6115 2935);
DISPLAY 0.617021 (-6115 2935);
PAINT ORANGE (-6115 2935);
FORCEPROP 2 LASTPIN (-6125 2875) $PN CC80
J 0
(-6115 2885);
DISPLAY 0.617021 (-6115 2885);
PAINT ORANGE (-6115 2885);
FORCEPROP 2 LASTPIN (-6125 2825) $PN CC82
J 0
(-6115 2835);
DISPLAY 0.617021 (-6115 2835);
PAINT ORANGE (-6115 2835);
FORCEPROP 2 LASTPIN (-6125 2775) $PN CD5
J 0
(-6115 2785);
DISPLAY 0.617021 (-6115 2785);
PAINT ORANGE (-6115 2785);
FORCEPROP 2 LASTPIN (-6125 2675) $PN CD63
J 0
(-6115 2685);
DISPLAY 0.617021 (-6115 2685);
PAINT ORANGE (-6115 2685);
FORCEPROP 2 LASTPIN (-6125 2625) $PN CD73
J 0
(-6115 2635);
DISPLAY 0.617021 (-6115 2635);
PAINT ORANGE (-6115 2635);
FORCEPROP 2 LASTPIN (-6125 2575) $PN CD75
J 0
(-6115 2585);
DISPLAY 0.617021 (-6115 2585);
PAINT ORANGE (-6115 2585);
FORCEPROP 2 LASTPIN (-6125 2525) $PN CD77
J 0
(-6115 2535);
DISPLAY 0.617021 (-6115 2535);
PAINT ORANGE (-6115 2535);
FORCEPROP 2 LASTPIN (-6125 2475) $PN CD79
J 0
(-6115 2485);
DISPLAY 0.617021 (-6115 2485);
PAINT ORANGE (-6115 2485);
FORCEPROP 2 LASTPIN (-6125 2425) $PN CD81
J 0
(-6115 2435);
DISPLAY 0.617021 (-6115 2435);
PAINT ORANGE (-6115 2435);
FORCEPROP 2 LASTPIN (-6125 2375) $PN CE10
J 0
(-6115 2385);
DISPLAY 0.617021 (-6115 2385);
PAINT ORANGE (-6115 2385);
FORCEPROP 2 LASTPIN (-6125 2325) $PN CE14
J 0
(-6115 2335);
DISPLAY 0.617021 (-6115 2335);
PAINT ORANGE (-6115 2335);
FORCEPROP 2 LASTPIN (-6125 2275) $PN CE20
J 0
(-6115 2285);
DISPLAY 0.617021 (-6115 2285);
PAINT ORANGE (-6115 2285);
FORCEPROP 2 LASTPIN (-6125 2225) $PN CE26
J 0
(-6115 2235);
DISPLAY 0.617021 (-6115 2235);
PAINT ORANGE (-6115 2235);
FORCEPROP 2 LASTPIN (-6125 2175) $PN CE62
J 0
(-6115 2185);
DISPLAY 0.617021 (-6115 2185);
PAINT ORANGE (-6115 2185);
FORCEPROP 2 LASTPIN (-6125 2125) $PN CE70
J 0
(-6115 2135);
DISPLAY 0.617021 (-6115 2135);
PAINT ORANGE (-6115 2135);
FORCEPROP 2 LASTPIN (-6125 2075) $PN CE82
J 0
(-6115 2085);
DISPLAY 0.617021 (-6115 2085);
PAINT ORANGE (-6115 2085);
FORCEPROP 2 LASTPIN (-6125 2025) $PN P53
J 0
(-6115 2035);
DISPLAY 0.617021 (-6115 2035);
PAINT ORANGE (-6115 2035);
FORCEPROP 2 LASTPIN (-6125 1975) $PN CF9
J 0
(-6115 1985);
DISPLAY 0.617021 (-6115 1985);
PAINT ORANGE (-6115 1985);
FORCEPROP 2 LASTPIN (-6125 1925) $PN CF63
J 0
(-6115 1935);
DISPLAY 0.617021 (-6115 1935);
PAINT ORANGE (-6115 1935);
FORCEPROP 2 LASTPIN (-6125 1875) $PN CF69
J 0
(-6115 1885);
DISPLAY 0.617021 (-6115 1885);
PAINT ORANGE (-6115 1885);
FORCEPROP 2 LASTPIN (-6125 1825) $PN CF71
J 0
(-6115 1835);
DISPLAY 0.617021 (-6115 1835);
PAINT ORANGE (-6115 1835);
FORCEPROP 2 LASTPIN (-6125 1775) $PN CF77
J 0
(-6115 1785);
DISPLAY 0.617021 (-6115 1785);
PAINT ORANGE (-6115 1785);
FORCEPROP 2 LASTPIN (-6125 1725) $PN CF83
J 0
(-6115 1735);
DISPLAY 0.617021 (-6115 1735);
PAINT ORANGE (-6115 1735);
FORCEPROP 2 LASTPIN (-6125 1675) $PN P51
J 0
(-6115 1685);
DISPLAY 0.617021 (-6115 1685);
PAINT ORANGE (-6115 1685);
FORCEPROP 2 LASTPIN (-6125 1625) $PN CG18
J 0
(-6115 1635);
DISPLAY 0.617021 (-6115 1635);
PAINT ORANGE (-6115 1635);
FORCEPROP 2 LASTPIN (-6125 1575) $PN CG22
J 0
(-6115 1585);
DISPLAY 0.617021 (-6115 1585);
PAINT ORANGE (-6115 1585);
FORCEPROP 2 LASTPIN (-6125 1525) $PN CG62
J 0
(-6115 1535);
DISPLAY 0.617021 (-6115 1535);
PAINT ORANGE (-6115 1535);
FORCEPROP 2 LASTPIN (-6125 1475) $PN CG68
J 0
(-6115 1485);
DISPLAY 0.617021 (-6115 1485);
PAINT ORANGE (-6115 1485);
FORCEPROP 2 LASTPIN (-6125 1425) $PN CG72
J 0
(-6115 1435);
DISPLAY 0.617021 (-6115 1435);
PAINT ORANGE (-6115 1435);
FORCEPROP 2 LASTPIN (-6125 1375) $PN CG80
J 0
(-6115 1385);
DISPLAY 0.617021 (-6115 1385);
PAINT ORANGE (-6115 1385);
FORCEPROP 2 LASTPIN (-6125 1325) $PN CH1
J 0
(-6115 1335);
DISPLAY 0.617021 (-6115 1335);
PAINT ORANGE (-6115 1335);
FORCEPROP 2 LASTPIN (-6125 1275) $PN CH3
J 0
(-6115 1285);
DISPLAY 0.617021 (-6115 1285);
PAINT ORANGE (-6115 1285);
FORCEPROP 2 LASTPIN (-6125 1225) $PN CH15
J 0
(-6115 1235);
DISPLAY 0.617021 (-6115 1235);
PAINT ORANGE (-6115 1235);
FORCEPROP 2 LASTPIN (-6125 1175) $PN CH19
J 0
(-6115 1185);
DISPLAY 0.617021 (-6115 1185);
PAINT ORANGE (-6115 1185);
FORCEPROP 2 LASTPIN (-6125 1125) $PN CH63
J 0
(-6115 1135);
DISPLAY 0.617021 (-6115 1135);
PAINT ORANGE (-6115 1135);
FORCEPROP 2 LASTPIN (-6125 1075) $PN CH67
J 0
(-6115 1085);
DISPLAY 0.617021 (-6115 1085);
PAINT ORANGE (-6115 1085);
FORCEPROP 2 LASTPIN (-6125 1025) $PN CH73
J 0
(-6115 1035);
DISPLAY 0.617021 (-6115 1035);
PAINT ORANGE (-6115 1035);
FORCEPROP 2 LASTPIN (-6125 975) $PN CH79
J 0
(-6115 985);
DISPLAY 0.617021 (-6115 985);
PAINT ORANGE (-6115 985);
FORCEPROP 2 LASTPIN (-6125 925) $PN CH81
J 0
(-6115 935);
DISPLAY 0.617021 (-6115 935);
PAINT ORANGE (-6115 935);
FORCEPROP 2 LASTPIN (-6125 875) $PN CH83
J 0
(-6115 885);
DISPLAY 0.617021 (-6115 885);
PAINT ORANGE (-6115 885);
FORCEPROP 2 LASTPIN (-6125 825) $PN CJ2
J 0
(-6115 835);
DISPLAY 0.617021 (-6115 835);
PAINT ORANGE (-6115 835);
FORCEPROP 2 LASTPIN (-6125 775) $PN CJ6
J 0
(-6115 785);
DISPLAY 0.617021 (-6115 785);
PAINT ORANGE (-6115 785);
FORCEPROP 2 LASTPIN (-6125 725) $PN CJ8
J 0
(-6115 735);
DISPLAY 0.617021 (-6115 735);
PAINT ORANGE (-6115 735);
FORCEPROP 2 LASTPIN (-6125 675) $PN CJ10
J 0
(-6115 685);
DISPLAY 0.617021 (-6115 685);
PAINT ORANGE (-6115 685);
FORCEPROP 2 LASTPIN (-6125 625) $PN CJ12
J 0
(-6115 635);
DISPLAY 0.617021 (-6115 635);
PAINT ORANGE (-6115 635);
FORCEPROP 2 LASTPIN (-6125 575) $PN P49
J 0
(-6115 585);
DISPLAY 0.617021 (-6115 585);
PAINT ORANGE (-6115 585);
FORCEPROP 2 LASTPIN (-6125 2725) $PN CD13
J 0
(-6115 2735);
DISPLAY 0.617021 (-6115 2735);
PAINT ORANGE (-6115 2735);
FORCEPROP 2 LASTPIN (-7325 4525) $PN BG74
J 2
(-7335 4535);
DISPLAY 0.617021 (-7335 4535);
PAINT ORANGE (-7335 4535);
FORCEPROP 2 LASTPIN (-7325 4475) $PN BG76
J 2
(-7335 4485);
DISPLAY 0.617021 (-7335 4485);
PAINT ORANGE (-7335 4485);
FORCEPROP 2 LASTPIN (-7325 4325) $PN BG82
J 2
(-7335 4335);
DISPLAY 0.617021 (-7335 4335);
PAINT ORANGE (-7335 4335);
FORCEPROP 2 LASTPIN (-7325 4425) $PN BG78
J 2
(-7335 4435);
DISPLAY 0.617021 (-7335 4435);
PAINT ORANGE (-7335 4435);
FORCEPROP 2 LASTPIN (-7325 4225) $PN BH9
J 2
(-7335 4235);
DISPLAY 0.617021 (-7335 4235);
PAINT ORANGE (-7335 4235);
FORCEPROP 1 LAST PACK_TYPE BGA1
J 0
(-7275 4825);
PAINT SKYBLUE (-7275 4825);
DISPLAY INVISIBLE (-7275 4825);
FORCEPROP 2 LAST SEC_TYPE BGA1
J 0
(-7275 4825);
DISPLAY 1.021277 (-7275 4825);
PAINT ORANGE (-7275 4825);
DISPLAY INVISIBLE (-7275 4825);
FORCEPROP 2 LAST CDS_LIB chpset_lib
J 0
(-6725 2525);
PAINT ORANGE (-6725 2525);
DISPLAY INVISIBLE (-6725 2525);
FORCEPROP 2 LAST SEC 27
J 0
(-7275 4825);
DISPLAY 0.680851 (-7275 4825);
PAINT MONO (-7275 4825);
DISPLAY INVISIBLE (-7275 4825);
FORCEPROP 2 LAST CDS_LOCATION U2D1
J 0
(-7275 4775);
DISPLAY 0.617021 (-7275 4775);
PAINT AQUA (-7275 4775);
DISPLAY INVISIBLE (-7275 4775);
FORCEPROP 1 LAST PATH I17
J 0
(-6725 4725);
PAINT GREEN (-6725 4725);
DISPLAY INVISIBLE (-6725 4725);
FORCEADD SKX_EXT_B..28
(-4925 2525);
FORCEPROP 1 LAST LOCATION U2D1
J 0
(-5475 4775);
DISPLAY 0.617021 (-5475 4775);
PAINT AQUA (-5475 4775);
FORCEPROP 1 LAST PART_NUMBER TBD
J 0
(-5475 375);
DISPLAY 0.617021 (-5475 375);
PAINT BLUE (-5475 375);
FORCEPROP 1 LAST MATERIAL IC
J 0
(-5475 4725);
DISPLAY 0.617021 (-5475 4725);
PAINT SKYBLUE (-5475 4725);
FORCEPROP 2 LASTPIN (-5525 4525) $PN P47
J 2
(-5535 4535);
DISPLAY 0.617021 (-5535 4535);
PAINT ORANGE (-5535 4535);
FORCEPROP 2 LASTPIN (-5525 4475) $PN CJ62
J 2
(-5535 4485);
DISPLAY 0.617021 (-5535 4485);
PAINT ORANGE (-5535 4485);
FORCEPROP 2 LASTPIN (-5525 4425) $PN CJ74
J 2
(-5535 4435);
DISPLAY 0.617021 (-5535 4435);
PAINT ORANGE (-5535 4435);
FORCEPROP 2 LASTPIN (-5525 4325) $PN CJ78
J 2
(-5535 4335);
DISPLAY 0.617021 (-5535 4335);
PAINT ORANGE (-5535 4335);
FORCEPROP 2 LASTPIN (-5525 4275) $PN CJ82
J 2
(-5535 4285);
DISPLAY 0.617021 (-5535 4285);
PAINT ORANGE (-5535 4285);
FORCEPROP 2 LASTPIN (-5525 4225) $PN CJ84
J 2
(-5535 4235);
DISPLAY 0.617021 (-5535 4235);
PAINT ORANGE (-5535 4235);
FORCEPROP 2 LASTPIN (-5525 4175) $PN CJ86
J 2
(-5535 4185);
DISPLAY 0.617021 (-5535 4185);
PAINT ORANGE (-5535 4185);
FORCEPROP 2 LASTPIN (-5525 4125) $PN CK11
J 2
(-5535 4135);
DISPLAY 0.617021 (-5535 4135);
PAINT ORANGE (-5535 4135);
FORCEPROP 2 LASTPIN (-5525 4075) $PN CK15
J 2
(-5535 4085);
DISPLAY 0.617021 (-5535 4085);
PAINT ORANGE (-5535 4085);
FORCEPROP 2 LASTPIN (-5525 4025) $PN CK21
J 2
(-5535 4035);
DISPLAY 0.617021 (-5535 4035);
PAINT ORANGE (-5535 4035);
FORCEPROP 2 LASTPIN (-5525 3975) $PN CK27
J 2
(-5535 3985);
DISPLAY 0.617021 (-5535 3985);
PAINT ORANGE (-5535 3985);
FORCEPROP 2 LASTPIN (-5525 3875) $PN CK65
J 2
(-5535 3885);
DISPLAY 0.617021 (-5535 3885);
PAINT ORANGE (-5535 3885);
FORCEPROP 2 LASTPIN (-5525 3825) $PN CK67
J 2
(-5535 3835);
DISPLAY 0.617021 (-5535 3835);
PAINT ORANGE (-5535 3835);
FORCEPROP 2 LASTPIN (-5525 3775) $PN CK69
J 2
(-5535 3785);
DISPLAY 0.617021 (-5535 3785);
PAINT ORANGE (-5535 3785);
FORCEPROP 2 LASTPIN (-5525 3725) $PN CK71
J 2
(-5535 3735);
DISPLAY 0.617021 (-5535 3735);
PAINT ORANGE (-5535 3735);
FORCEPROP 2 LASTPIN (-5525 3675) $PN CK73
J 2
(-5535 3685);
DISPLAY 0.617021 (-5535 3685);
PAINT ORANGE (-5535 3685);
FORCEPROP 2 LASTPIN (-5525 3625) $PN CK75
J 2
(-5535 3635);
DISPLAY 0.617021 (-5535 3635);
PAINT ORANGE (-5535 3635);
FORCEPROP 2 LASTPIN (-5525 3575) $PN CK83
J 2
(-5535 3585);
DISPLAY 0.617021 (-5535 3585);
PAINT ORANGE (-5535 3585);
FORCEPROP 2 LASTPIN (-5525 3525) $PN CK85
J 2
(-5535 3535);
DISPLAY 0.617021 (-5535 3535);
PAINT ORANGE (-5535 3535);
FORCEPROP 2 LASTPIN (-5525 3425) $PN CL14
J 2
(-5535 3435);
DISPLAY 0.617021 (-5535 3435);
PAINT ORANGE (-5535 3435);
FORCEPROP 2 LASTPIN (-5525 3375) $PN CL18
J 2
(-5535 3385);
DISPLAY 0.617021 (-5535 3385);
PAINT ORANGE (-5535 3385);
FORCEPROP 2 LASTPIN (-5525 3325) $PN P45
J 2
(-5535 3335);
DISPLAY 0.617021 (-5535 3335);
PAINT ORANGE (-5535 3335);
FORCEPROP 2 LASTPIN (-5525 3275) $PN H63
J 2
(-5535 3285);
DISPLAY 0.617021 (-5535 3285);
PAINT ORANGE (-5535 3285);
FORCEPROP 2 LASTPIN (-5525 3225) $PN CL62
J 2
(-5535 3235);
DISPLAY 0.617021 (-5535 3235);
PAINT ORANGE (-5535 3235);
FORCEPROP 2 LASTPIN (-5525 3175) $PN CL64
J 2
(-5535 3185);
DISPLAY 0.617021 (-5535 3185);
PAINT ORANGE (-5535 3185);
FORCEPROP 2 LASTPIN (-5525 3125) $PN CL66
J 2
(-5535 3135);
DISPLAY 0.617021 (-5535 3135);
PAINT ORANGE (-5535 3135);
FORCEPROP 2 LASTPIN (-5525 3075) $PN CL74
J 2
(-5535 3085);
DISPLAY 0.617021 (-5535 3085);
PAINT ORANGE (-5535 3085);
FORCEPROP 2 LASTPIN (-5525 3025) $PN CL76
J 2
(-5535 3035);
DISPLAY 0.617021 (-5535 3035);
PAINT ORANGE (-5535 3035);
FORCEPROP 2 LASTPIN (-5525 2975) $PN CL78
J 2
(-5535 2985);
DISPLAY 0.617021 (-5535 2985);
PAINT ORANGE (-5535 2985);
FORCEPROP 2 LASTPIN (-5525 2925) $PN CL80
J 2
(-5535 2935);
DISPLAY 0.617021 (-5535 2935);
PAINT ORANGE (-5535 2935);
FORCEPROP 2 LASTPIN (-5525 2875) $PN CM19
J 2
(-5535 2885);
DISPLAY 0.617021 (-5535 2885);
PAINT ORANGE (-5535 2885);
FORCEPROP 2 LASTPIN (-5525 2825) $PN CM29
J 2
(-5535 2835);
DISPLAY 0.617021 (-5535 2835);
PAINT ORANGE (-5535 2835);
FORCEPROP 2 LASTPIN (-5525 2775) $PN CM5
J 2
(-5535 2785);
DISPLAY 0.617021 (-5535 2785);
PAINT ORANGE (-5535 2785);
FORCEPROP 2 LASTPIN (-5525 2725) $PN CM31
J 2
(-5535 2735);
DISPLAY 0.617021 (-5535 2735);
PAINT ORANGE (-5535 2735);
FORCEPROP 2 LASTPIN (-5525 2675) $PN CM61
J 2
(-5535 2685);
DISPLAY 0.617021 (-5535 2685);
PAINT ORANGE (-5535 2685);
FORCEPROP 2 LASTPIN (-5525 2625) $PN CM63
J 2
(-5535 2635);
DISPLAY 0.617021 (-5535 2635);
PAINT ORANGE (-5535 2635);
FORCEPROP 2 LASTPIN (-5525 2575) $PN CM67
J 2
(-5535 2585);
DISPLAY 0.617021 (-5535 2585);
PAINT ORANGE (-5535 2585);
FORCEPROP 2 LASTPIN (-5525 2525) $PN CM73
J 2
(-5535 2535);
DISPLAY 0.617021 (-5535 2535);
PAINT ORANGE (-5535 2535);
FORCEPROP 2 LASTPIN (-5525 2475) $PN CM77
J 2
(-5535 2485);
DISPLAY 0.617021 (-5535 2485);
PAINT ORANGE (-5535 2485);
FORCEPROP 2 LASTPIN (-5525 2425) $PN CM83
J 2
(-5535 2435);
DISPLAY 0.617021 (-5535 2435);
PAINT ORANGE (-5535 2435);
FORCEPROP 2 LASTPIN (-5525 2375) $PN CM85
J 2
(-5535 2385);
DISPLAY 0.617021 (-5535 2385);
PAINT ORANGE (-5535 2385);
FORCEPROP 2 LASTPIN (-5525 2325) $PN CN2
J 2
(-5535 2335);
DISPLAY 0.617021 (-5535 2335);
PAINT ORANGE (-5535 2335);
FORCEPROP 2 LASTPIN (-5525 2275) $PN CN12
J 2
(-5535 2285);
DISPLAY 0.617021 (-5535 2285);
PAINT ORANGE (-5535 2285);
FORCEPROP 2 LASTPIN (-5525 2225) $PN H61
J 2
(-5535 2235);
DISPLAY 0.617021 (-5535 2235);
PAINT ORANGE (-5535 2235);
FORCEPROP 2 LASTPIN (-5525 2175) $PN CN26
J 2
(-5535 2185);
DISPLAY 0.617021 (-5535 2185);
PAINT ORANGE (-5535 2185);
FORCEPROP 2 LASTPIN (-5525 2125) $PN CN32
J 2
(-5535 2135);
DISPLAY 0.617021 (-5535 2135);
PAINT ORANGE (-5535 2135);
FORCEPROP 2 LASTPIN (-5525 2075) $PN CN60
J 2
(-5535 2085);
DISPLAY 0.617021 (-5535 2085);
PAINT ORANGE (-5535 2085);
FORCEPROP 2 LASTPIN (-5525 2025) $PN CN62
J 2
(-5535 2035);
DISPLAY 0.617021 (-5535 2035);
PAINT ORANGE (-5535 2035);
FORCEPROP 2 LASTPIN (-5525 1975) $PN CN68
J 2
(-5535 1985);
DISPLAY 0.617021 (-5535 1985);
PAINT ORANGE (-5535 1985);
FORCEPROP 2 LASTPIN (-5525 1925) $PN CN78
J 2
(-5535 1935);
DISPLAY 0.617021 (-5535 1935);
PAINT ORANGE (-5535 1935);
FORCEPROP 2 LASTPIN (-5525 1875) $PN CP1
J 2
(-5535 1885);
DISPLAY 0.617021 (-5535 1885);
PAINT ORANGE (-5535 1885);
FORCEPROP 2 LASTPIN (-5525 1825) $PN H59
J 2
(-5535 1835);
DISPLAY 0.617021 (-5535 1835);
PAINT ORANGE (-5535 1835);
FORCEPROP 2 LASTPIN (-5525 1775) $PN CP25
J 2
(-5535 1785);
DISPLAY 0.617021 (-5535 1785);
PAINT ORANGE (-5535 1785);
FORCEPROP 2 LASTPIN (-5525 1725) $PN CP59
J 2
(-5535 1735);
DISPLAY 0.617021 (-5535 1735);
PAINT ORANGE (-5535 1735);
FORCEPROP 2 LASTPIN (-5525 1675) $PN CP69
J 2
(-5535 1685);
DISPLAY 0.617021 (-5535 1685);
PAINT ORANGE (-5535 1685);
FORCEPROP 2 LASTPIN (-5525 1625) $PN CP73
J 2
(-5535 1635);
DISPLAY 0.617021 (-5535 1635);
PAINT ORANGE (-5535 1635);
FORCEPROP 2 LASTPIN (-5525 1575) $PN CP75
J 2
(-5535 1585);
DISPLAY 0.617021 (-5535 1585);
PAINT ORANGE (-5535 1585);
FORCEPROP 2 LASTPIN (-5525 1525) $PN CP81
J 2
(-5535 1535);
DISPLAY 0.617021 (-5535 1535);
PAINT ORANGE (-5535 1535);
FORCEPROP 2 LASTPIN (-5525 1475) $PN CP83
J 2
(-5535 1485);
DISPLAY 0.617021 (-5535 1485);
PAINT ORANGE (-5535 1485);
FORCEPROP 2 LASTPIN (-5525 1425) $PN CR6
J 2
(-5535 1435);
DISPLAY 0.617021 (-5535 1435);
PAINT ORANGE (-5535 1435);
FORCEPROP 2 LASTPIN (-5525 1375) $PN CR10
J 2
(-5535 1385);
DISPLAY 0.617021 (-5535 1385);
PAINT ORANGE (-5535 1385);
FORCEPROP 2 LASTPIN (-5525 1325) $PN CR22
J 2
(-5535 1335);
DISPLAY 0.617021 (-5535 1335);
PAINT ORANGE (-5535 1335);
FORCEPROP 2 LASTPIN (-5525 1275) $PN CR24
J 2
(-5535 1285);
DISPLAY 0.617021 (-5535 1285);
PAINT ORANGE (-5535 1285);
FORCEPROP 2 LASTPIN (-5525 1225) $PN CR32
J 2
(-5535 1235);
DISPLAY 0.617021 (-5535 1235);
PAINT ORANGE (-5535 1235);
FORCEPROP 2 LASTPIN (-5525 1175) $PN CR58
J 2
(-5535 1185);
DISPLAY 0.617021 (-5535 1185);
PAINT ORANGE (-5535 1185);
FORCEPROP 2 LASTPIN (-5525 1125) $PN CR62
J 2
(-5535 1135);
DISPLAY 0.617021 (-5535 1135);
PAINT ORANGE (-5535 1135);
FORCEPROP 2 LASTPIN (-5525 1075) $PN CR64
J 2
(-5535 1085);
DISPLAY 0.617021 (-5535 1085);
PAINT ORANGE (-5535 1085);
FORCEPROP 2 LASTPIN (-5525 1025) $PN CR66
J 2
(-5535 1035);
DISPLAY 0.617021 (-5535 1035);
PAINT ORANGE (-5535 1035);
FORCEPROP 2 LASTPIN (-5525 975) $PN CR68
J 2
(-5535 985);
DISPLAY 0.617021 (-5535 985);
PAINT ORANGE (-5535 985);
FORCEPROP 2 LASTPIN (-5525 925) $PN CR78
J 2
(-5535 935);
DISPLAY 0.617021 (-5535 935);
PAINT ORANGE (-5535 935);
FORCEPROP 2 LASTPIN (-5525 875) $PN CR86
J 2
(-5535 885);
DISPLAY 0.617021 (-5535 885);
PAINT ORANGE (-5535 885);
FORCEPROP 2 LASTPIN (-5525 825) $PN H57
J 2
(-5535 835);
DISPLAY 0.617021 (-5535 835);
PAINT ORANGE (-5535 835);
FORCEPROP 2 LASTPIN (-5525 775) $PN CT13
J 2
(-5535 785);
DISPLAY 0.617021 (-5535 785);
PAINT ORANGE (-5535 785);
FORCEPROP 2 LASTPIN (-5525 725) $PN CT19
J 2
(-5535 735);
DISPLAY 0.617021 (-5535 735);
PAINT ORANGE (-5535 735);
FORCEPROP 2 LASTPIN (-5525 675) $PN CT27
J 2
(-5535 685);
DISPLAY 0.617021 (-5535 685);
PAINT ORANGE (-5535 685);
FORCEPROP 2 LASTPIN (-5525 625) $PN CT29
J 2
(-5535 635);
DISPLAY 0.617021 (-5535 635);
PAINT ORANGE (-5535 635);
FORCEPROP 2 LASTPIN (-5525 575) $PN CT33
J 2
(-5535 585);
DISPLAY 0.617021 (-5535 585);
PAINT ORANGE (-5535 585);
FORCEPROP 2 LASTPIN (-4325 4525) $PN CT35
J 0
(-4315 4535);
DISPLAY 0.617021 (-4315 4535);
PAINT ORANGE (-4315 4535);
FORCEPROP 2 LASTPIN (-4325 4475) $PN CT57
J 0
(-4315 4485);
DISPLAY 0.617021 (-4315 4485);
PAINT ORANGE (-4315 4485);
FORCEPROP 2 LASTPIN (-4325 4425) $PN CT73
J 0
(-4315 4435);
DISPLAY 0.617021 (-4315 4435);
PAINT ORANGE (-4315 4435);
FORCEPROP 2 LASTPIN (-4325 4375) $PN CT79
J 0
(-4315 4385);
DISPLAY 0.617021 (-4315 4385);
PAINT ORANGE (-4315 4385);
FORCEPROP 2 LASTPIN (-4325 4325) $PN CT83
J 0
(-4315 4335);
DISPLAY 0.617021 (-4315 4335);
PAINT ORANGE (-4315 4335);
FORCEPROP 2 LASTPIN (-4325 4275) $PN CT85
J 0
(-4315 4285);
DISPLAY 0.617021 (-4315 4285);
PAINT ORANGE (-4315 4285);
FORCEPROP 2 LASTPIN (-4325 4225) $PN CU4
J 0
(-4315 4235);
DISPLAY 0.617021 (-4315 4235);
PAINT ORANGE (-4315 4235);
FORCEPROP 2 LASTPIN (-4325 4175) $PN CU22
J 0
(-4315 4185);
DISPLAY 0.617021 (-4315 4185);
PAINT ORANGE (-4315 4185);
FORCEPROP 2 LASTPIN (-4325 4125) $PN CU28
J 0
(-4315 4135);
DISPLAY 0.617021 (-4315 4135);
PAINT ORANGE (-4315 4135);
FORCEPROP 2 LASTPIN (-4325 4075) $PN CU30
J 0
(-4315 4085);
DISPLAY 0.617021 (-4315 4085);
PAINT ORANGE (-4315 4085);
FORCEPROP 2 LASTPIN (-4325 4025) $PN CU34
J 0
(-4315 4035);
DISPLAY 0.617021 (-4315 4035);
PAINT ORANGE (-4315 4035);
FORCEPROP 2 LASTPIN (-4325 3975) $PN CU36
J 0
(-4315 3985);
DISPLAY 0.617021 (-4315 3985);
PAINT ORANGE (-4315 3985);
FORCEPROP 2 LASTPIN (-4325 3925) $PN CU56
J 0
(-4315 3935);
DISPLAY 0.617021 (-4315 3935);
PAINT ORANGE (-4315 3935);
FORCEPROP 2 LASTPIN (-4325 3875) $PN CU62
J 0
(-4315 3885);
DISPLAY 0.617021 (-4315 3885);
PAINT ORANGE (-4315 3885);
FORCEPROP 2 LASTPIN (-4325 3825) $PN CU68
J 0
(-4315 3835);
DISPLAY 0.617021 (-4315 3835);
PAINT ORANGE (-4315 3835);
FORCEPROP 2 LASTPIN (-4325 3775) $PN CU76
J 0
(-4315 3785);
DISPLAY 0.617021 (-4315 3785);
PAINT ORANGE (-4315 3785);
FORCEPROP 2 LASTPIN (-4325 3725) $PN CU78
J 0
(-4315 3735);
DISPLAY 0.617021 (-4315 3735);
PAINT ORANGE (-4315 3735);
FORCEPROP 2 LASTPIN (-4325 3675) $PN CU80
J 0
(-4315 3685);
DISPLAY 0.617021 (-4315 3685);
PAINT ORANGE (-4315 3685);
FORCEPROP 2 LASTPIN (-4325 3625) $PN CU82
J 0
(-4315 3635);
DISPLAY 0.617021 (-4315 3635);
PAINT ORANGE (-4315 3635);
FORCEPROP 2 LASTPIN (-4325 3525) $PN CV1
J 0
(-4315 3535);
DISPLAY 0.617021 (-4315 3535);
PAINT ORANGE (-4315 3535);
FORCEPROP 2 LASTPIN (-4325 3475) $PN H55
J 0
(-4315 3485);
DISPLAY 0.617021 (-4315 3485);
PAINT ORANGE (-4315 3485);
FORCEPROP 2 LASTPIN (-4325 3425) $PN CV17
J 0
(-4315 3435);
DISPLAY 0.617021 (-4315 3435);
PAINT ORANGE (-4315 3435);
FORCEPROP 2 LASTPIN (-4325 3375) $PN CV25
J 0
(-4315 3385);
DISPLAY 0.617021 (-4315 3385);
PAINT ORANGE (-4315 3385);
FORCEPROP 2 LASTPIN (-4325 3325) $PN CV27
J 0
(-4315 3335);
DISPLAY 0.617021 (-4315 3335);
PAINT ORANGE (-4315 3335);
FORCEPROP 2 LASTPIN (-4325 3275) $PN CV31
J 0
(-4315 3285);
DISPLAY 0.617021 (-4315 3285);
PAINT ORANGE (-4315 3285);
FORCEPROP 2 LASTPIN (-4325 3225) $PN CV33
J 0
(-4315 3235);
DISPLAY 0.617021 (-4315 3235);
PAINT ORANGE (-4315 3235);
FORCEPROP 2 LASTPIN (-4325 3175) $PN CV37
J 0
(-4315 3185);
DISPLAY 0.617021 (-4315 3185);
PAINT ORANGE (-4315 3185);
FORCEPROP 2 LASTPIN (-4325 3125) $PN CV39
J 0
(-4315 3135);
DISPLAY 0.617021 (-4315 3135);
PAINT ORANGE (-4315 3135);
FORCEPROP 2 LASTPIN (-4325 3075) $PN CV41
J 0
(-4315 3085);
DISPLAY 0.617021 (-4315 3085);
PAINT ORANGE (-4315 3085);
FORCEPROP 2 LASTPIN (-4325 3025) $PN CV53
J 0
(-4315 3035);
DISPLAY 0.617021 (-4315 3035);
PAINT ORANGE (-4315 3035);
FORCEPROP 2 LASTPIN (-4325 2975) $PN CV55
J 0
(-4315 2985);
DISPLAY 0.617021 (-4315 2985);
PAINT ORANGE (-4315 2985);
FORCEPROP 2 LASTPIN (-4325 2925) $PN CV63
J 0
(-4315 2935);
DISPLAY 0.617021 (-4315 2935);
PAINT ORANGE (-4315 2935);
FORCEPROP 2 LASTPIN (-4325 2875) $PN CV67
J 0
(-4315 2885);
DISPLAY 0.617021 (-4315 2885);
PAINT ORANGE (-4315 2885);
FORCEPROP 2 LASTPIN (-4325 2825) $PN CV73
J 0
(-4315 2835);
DISPLAY 0.617021 (-4315 2835);
PAINT ORANGE (-4315 2835);
FORCEPROP 2 LASTPIN (-4325 2775) $PN CV79
J 0
(-4315 2785);
DISPLAY 0.617021 (-4315 2785);
PAINT ORANGE (-4315 2785);
FORCEPROP 2 LASTPIN (-4325 2725) $PN CV81
J 0
(-4315 2735);
DISPLAY 0.617021 (-4315 2735);
PAINT ORANGE (-4315 2735);
FORCEPROP 2 LASTPIN (-4325 2675) $PN CV83
J 0
(-4315 2685);
DISPLAY 0.617021 (-4315 2685);
PAINT ORANGE (-4315 2685);
FORCEPROP 2 LASTPIN (-4325 2625) $PN CW12
J 0
(-4315 2635);
DISPLAY 0.617021 (-4315 2635);
PAINT ORANGE (-4315 2635);
FORCEPROP 2 LASTPIN (-4325 2575) $PN CW26
J 0
(-4315 2585);
DISPLAY 0.617021 (-4315 2585);
PAINT ORANGE (-4315 2585);
FORCEPROP 2 LASTPIN (-4325 2525) $PN CW32
J 0
(-4315 2535);
DISPLAY 0.617021 (-4315 2535);
PAINT ORANGE (-4315 2535);
FORCEPROP 2 LASTPIN (-4325 2475) $PN CW38
J 0
(-4315 2485);
DISPLAY 0.617021 (-4315 2485);
PAINT ORANGE (-4315 2485);
FORCEPROP 2 LASTPIN (-4325 2425) $PN CW40
J 0
(-4315 2435);
DISPLAY 0.617021 (-4315 2435);
PAINT ORANGE (-4315 2435);
FORCEPROP 2 LASTPIN (-4325 2375) $PN CW42
J 0
(-4315 2385);
DISPLAY 0.617021 (-4315 2385);
PAINT ORANGE (-4315 2385);
FORCEPROP 2 LASTPIN (-4325 2325) $PN CW52
J 0
(-4315 2335);
DISPLAY 0.617021 (-4315 2335);
PAINT ORANGE (-4315 2335);
FORCEPROP 2 LASTPIN (-4325 2275) $PN CW54
J 0
(-4315 2285);
DISPLAY 0.617021 (-4315 2285);
PAINT ORANGE (-4315 2285);
FORCEPROP 2 LASTPIN (-4325 2225) $PN CW64
J 0
(-4315 2235);
DISPLAY 0.617021 (-4315 2235);
PAINT ORANGE (-4315 2235);
FORCEPROP 2 LASTPIN (-4325 2175) $PN CW66
J 0
(-4315 2185);
DISPLAY 0.617021 (-4315 2185);
PAINT ORANGE (-4315 2185);
FORCEPROP 2 LASTPIN (-4325 2125) $PN CW68
J 0
(-4315 2135);
DISPLAY 0.617021 (-4315 2135);
PAINT ORANGE (-4315 2135);
FORCEPROP 2 LASTPIN (-4325 2075) $PN CW74
J 0
(-4315 2085);
DISPLAY 0.617021 (-4315 2085);
PAINT ORANGE (-4315 2085);
FORCEPROP 2 LASTPIN (-4325 2025) $PN CW78
J 0
(-4315 2035);
DISPLAY 0.617021 (-4315 2035);
PAINT ORANGE (-4315 2035);
FORCEPROP 2 LASTPIN (-4325 1975) $PN CW82
J 0
(-4315 1985);
DISPLAY 0.617021 (-4315 1985);
PAINT ORANGE (-4315 1985);
FORCEPROP 2 LASTPIN (-4325 1925) $PN CY1
J 0
(-4315 1935);
DISPLAY 0.617021 (-4315 1935);
PAINT ORANGE (-4315 1935);
FORCEPROP 2 LASTPIN (-4325 1875) $PN CY9
J 0
(-4315 1885);
DISPLAY 0.617021 (-4315 1885);
PAINT ORANGE (-4315 1885);
FORCEPROP 2 LASTPIN (-4325 1825) $PN CY13
J 0
(-4315 1835);
DISPLAY 0.617021 (-4315 1835);
PAINT ORANGE (-4315 1835);
FORCEPROP 2 LASTPIN (-4325 1775) $PN CY15
J 0
(-4315 1785);
DISPLAY 0.617021 (-4315 1785);
PAINT ORANGE (-4315 1785);
FORCEPROP 2 LASTPIN (-4325 1725) $PN CY21
J 0
(-4315 1735);
DISPLAY 0.617021 (-4315 1735);
PAINT ORANGE (-4315 1735);
FORCEPROP 2 LASTPIN (-4325 1675) $PN CY41
J 0
(-4315 1685);
DISPLAY 0.617021 (-4315 1685);
PAINT ORANGE (-4315 1685);
FORCEPROP 2 LASTPIN (-4325 1625) $PN CY45
J 0
(-4315 1635);
DISPLAY 0.617021 (-4315 1635);
PAINT ORANGE (-4315 1635);
FORCEPROP 2 LASTPIN (-4325 1575) $PN CY51
J 0
(-4315 1585);
DISPLAY 0.617021 (-4315 1585);
PAINT ORANGE (-4315 1585);
FORCEPROP 2 LASTPIN (-4325 1525) $PN CY59
J 0
(-4315 1535);
DISPLAY 0.617021 (-4315 1535);
PAINT ORANGE (-4315 1535);
FORCEPROP 2 LASTPIN (-4325 1475) $PN CY61
J 0
(-4315 1485);
DISPLAY 0.617021 (-4315 1485);
PAINT ORANGE (-4315 1485);
FORCEPROP 2 LASTPIN (-4325 1425) $PN CY65
J 0
(-4315 1435);
DISPLAY 0.617021 (-4315 1435);
PAINT ORANGE (-4315 1435);
FORCEPROP 2 LASTPIN (-4325 1375) $PN CY69
J 0
(-4315 1385);
DISPLAY 0.617021 (-4315 1385);
PAINT ORANGE (-4315 1385);
FORCEPROP 2 LASTPIN (-4325 1325) $PN CY75
J 0
(-4315 1335);
DISPLAY 0.617021 (-4315 1335);
PAINT ORANGE (-4315 1335);
FORCEPROP 2 LASTPIN (-4325 1275) $PN CY77
J 0
(-4315 1285);
DISPLAY 0.617021 (-4315 1285);
PAINT ORANGE (-4315 1285);
FORCEPROP 2 LASTPIN (-4325 1225) $PN CY83
J 0
(-4315 1235);
DISPLAY 0.617021 (-4315 1235);
PAINT ORANGE (-4315 1235);
FORCEPROP 2 LASTPIN (-4325 1175) $PN CY85
J 0
(-4315 1185);
DISPLAY 0.617021 (-4315 1185);
PAINT ORANGE (-4315 1185);
FORCEPROP 2 LASTPIN (-4325 1125) $PN DA6
J 0
(-4315 1135);
DISPLAY 0.617021 (-4315 1135);
PAINT ORANGE (-4315 1135);
FORCEPROP 2 LASTPIN (-4325 1075) $PN H53
J 0
(-4315 1085);
DISPLAY 0.617021 (-4315 1085);
PAINT ORANGE (-4315 1085);
FORCEPROP 2 LASTPIN (-4325 1025) $PN DA18
J 0
(-4315 1035);
DISPLAY 0.617021 (-4315 1035);
PAINT ORANGE (-4315 1035);
FORCEPROP 2 LASTPIN (-4325 975) $PN DA26
J 0
(-4315 985);
DISPLAY 0.617021 (-4315 985);
PAINT ORANGE (-4315 985);
FORCEPROP 2 LASTPIN (-4325 925) $PN DA28
J 0
(-4315 935);
DISPLAY 0.617021 (-4315 935);
PAINT ORANGE (-4315 935);
FORCEPROP 2 LASTPIN (-4325 875) $PN DA30
J 0
(-4315 885);
DISPLAY 0.617021 (-4315 885);
PAINT ORANGE (-4315 885);
FORCEPROP 2 LASTPIN (-4325 825) $PN DA32
J 0
(-4315 835);
DISPLAY 0.617021 (-4315 835);
PAINT ORANGE (-4315 835);
FORCEPROP 2 LASTPIN (-4325 775) $PN DA34
J 0
(-4315 785);
DISPLAY 0.617021 (-4315 785);
PAINT ORANGE (-4315 785);
FORCEPROP 2 LASTPIN (-4325 725) $PN DA36
J 0
(-4315 735);
DISPLAY 0.617021 (-4315 735);
PAINT ORANGE (-4315 735);
FORCEPROP 2 LASTPIN (-4325 675) $PN DA38
J 0
(-4315 685);
DISPLAY 0.617021 (-4315 685);
PAINT ORANGE (-4315 685);
FORCEPROP 2 LASTPIN (-4325 625) $PN DA44
J 0
(-4315 635);
DISPLAY 0.617021 (-4315 635);
PAINT ORANGE (-4315 635);
FORCEPROP 2 LASTPIN (-4325 575) $PN DA46
J 0
(-4315 585);
DISPLAY 0.617021 (-4315 585);
PAINT ORANGE (-4315 585);
FORCEPROP 2 LASTPIN (-5525 4375) $PN CJ76
J 2
(-5535 4385);
DISPLAY 0.617021 (-5535 4385);
PAINT ORANGE (-5535 4385);
FORCEPROP 2 LASTPIN (-5525 3925) $PN CK63
J 2
(-5535 3935);
DISPLAY 0.617021 (-5535 3935);
PAINT ORANGE (-5535 3935);
FORCEPROP 2 LASTPIN (-4325 3575) $PN CU86
J 0
(-4315 3585);
DISPLAY 0.617021 (-4315 3585);
PAINT ORANGE (-4315 3585);
FORCEPROP 2 LASTPIN (-5525 3475) $PN CL8
J 2
(-5535 3485);
DISPLAY 0.617021 (-5535 3485);
PAINT ORANGE (-5535 3485);
FORCEPROP 1 LAST PACK_TYPE BGA1
J 0
(-5475 4825);
PAINT SKYBLUE (-5475 4825);
DISPLAY INVISIBLE (-5475 4825);
FORCEPROP 2 LAST SEC_TYPE BGA1
J 0
(-5475 4825);
DISPLAY 1.021277 (-5475 4825);
PAINT ORANGE (-5475 4825);
DISPLAY INVISIBLE (-5475 4825);
FORCEPROP 2 LAST CDS_LIB chpset_lib
J 0
(-4925 2525);
PAINT ORANGE (-4925 2525);
DISPLAY INVISIBLE (-4925 2525);
FORCEPROP 2 LAST SEC 28
J 0
(-5475 4825);
DISPLAY 0.680851 (-5475 4825);
PAINT MONO (-5475 4825);
DISPLAY INVISIBLE (-5475 4825);
FORCEPROP 2 LAST CDS_LOCATION U2D1
J 0
(-5475 4775);
DISPLAY 0.617021 (-5475 4775);
PAINT AQUA (-5475 4775);
DISPLAY INVISIBLE (-5475 4775);
FORCEPROP 1 LAST PATH I18
J 0
(-4925 4725);
PAINT GREEN (-4925 4725);
DISPLAY INVISIBLE (-4925 4725);
FORCEADD SKX_EXT_B..29
(-3050 2525);
FORCEPROP 1 LAST LOCATION U2D1
J 0
(-3600 4775);
DISPLAY 0.617021 (-3600 4775);
PAINT AQUA (-3600 4775);
FORCEPROP 1 LAST PART_NUMBER TBD
J 0
(-3600 375);
DISPLAY 0.617021 (-3600 375);
PAINT BLUE (-3600 375);
FORCEPROP 1 LAST MATERIAL IC
J 0
(-3600 4725);
DISPLAY 0.617021 (-3600 4725);
PAINT SKYBLUE (-3600 4725);
FORCEPROP 2 LASTPIN (-3650 4525) $PN DA48
J 2
(-3660 4535);
DISPLAY 0.617021 (-3660 4535);
PAINT ORANGE (-3660 4535);
FORCEPROP 2 LASTPIN (-3650 4475) $PN DA50
J 2
(-3660 4485);
DISPLAY 0.617021 (-3660 4485);
PAINT ORANGE (-3660 4485);
FORCEPROP 2 LASTPIN (-3650 4425) $PN DA64
J 2
(-3660 4435);
DISPLAY 0.617021 (-3660 4435);
PAINT ORANGE (-3660 4435);
FORCEPROP 2 LASTPIN (-3650 4375) $PN DA70
J 2
(-3660 4385);
DISPLAY 0.617021 (-3660 4385);
PAINT ORANGE (-3660 4385);
FORCEPROP 2 LASTPIN (-3650 4325) $PN DA74
J 2
(-3660 4335);
DISPLAY 0.617021 (-3660 4335);
PAINT ORANGE (-3660 4335);
FORCEPROP 2 LASTPIN (-3650 4275) $PN DA76
J 2
(-3660 4285);
DISPLAY 0.617021 (-3660 4285);
PAINT ORANGE (-3660 4285);
FORCEPROP 2 LASTPIN (-3650 4225) $PN DA78
J 2
(-3660 4235);
DISPLAY 0.617021 (-3660 4235);
PAINT ORANGE (-3660 4235);
FORCEPROP 2 LASTPIN (-3650 4175) $PN DA80
J 2
(-3660 4185);
DISPLAY 0.617021 (-3660 4185);
PAINT ORANGE (-3660 4185);
FORCEPROP 2 LASTPIN (-3650 4125) $PN DB3
J 2
(-3660 4135);
DISPLAY 0.617021 (-3660 4135);
PAINT ORANGE (-3660 4135);
FORCEPROP 2 LASTPIN (-3650 4075) $PN DB13
J 2
(-3660 4085);
DISPLAY 0.617021 (-3660 4085);
PAINT ORANGE (-3660 4085);
FORCEPROP 2 LASTPIN (-3650 4025) $PN DB17
J 2
(-3660 4035);
DISPLAY 0.617021 (-3660 4035);
PAINT ORANGE (-3660 4035);
FORCEPROP 2 LASTPIN (-3650 3975) $PN DB23
J 2
(-3660 3985);
DISPLAY 0.617021 (-3660 3985);
PAINT ORANGE (-3660 3985);
FORCEPROP 2 LASTPIN (-3650 3925) $PN DB25
J 2
(-3660 3935);
DISPLAY 0.617021 (-3660 3935);
PAINT ORANGE (-3660 3935);
FORCEPROP 2 LASTPIN (-3650 3875) $PN DB39
J 2
(-3660 3885);
DISPLAY 0.617021 (-3660 3885);
PAINT ORANGE (-3660 3885);
FORCEPROP 2 LASTPIN (-3650 3825) $PN DB41
J 2
(-3660 3835);
DISPLAY 0.617021 (-3660 3835);
PAINT ORANGE (-3660 3835);
FORCEPROP 2 LASTPIN (-3650 3775) $PN DB47
J 2
(-3660 3785);
DISPLAY 0.617021 (-3660 3785);
PAINT ORANGE (-3660 3785);
FORCEPROP 2 LASTPIN (-3650 3725) $PN DB49
J 2
(-3660 3735);
DISPLAY 0.617021 (-3660 3735);
PAINT ORANGE (-3660 3735);
FORCEPROP 2 LASTPIN (-3650 3675) $PN DB73
J 2
(-3660 3685);
DISPLAY 0.617021 (-3660 3685);
PAINT ORANGE (-3660 3685);
FORCEPROP 2 LASTPIN (-3650 3625) $PN DB77
J 2
(-3660 3635);
DISPLAY 0.617021 (-3660 3635);
PAINT ORANGE (-3660 3635);
FORCEPROP 2 LASTPIN (-3650 3575) $PN DB83
J 2
(-3660 3585);
DISPLAY 0.617021 (-3660 3585);
PAINT ORANGE (-3660 3585);
FORCEPROP 2 LASTPIN (-3650 3525) $PN DB85
J 2
(-3660 3535);
DISPLAY 0.617021 (-3660 3535);
PAINT ORANGE (-3660 3535);
FORCEPROP 2 LASTPIN (-3650 3475) $PN DC14
J 2
(-3660 3485);
DISPLAY 0.617021 (-3660 3485);
PAINT ORANGE (-3660 3485);
FORCEPROP 2 LASTPIN (-3650 3425) $PN DC24
J 2
(-3660 3435);
DISPLAY 0.617021 (-3660 3435);
PAINT ORANGE (-3660 3435);
FORCEPROP 2 LASTPIN (-3650 3375) $PN DC26
J 2
(-3660 3385);
DISPLAY 0.617021 (-3660 3385);
PAINT ORANGE (-3660 3385);
FORCEPROP 2 LASTPIN (-3650 3325) $PN DC32
J 2
(-3660 3335);
DISPLAY 0.617021 (-3660 3335);
PAINT ORANGE (-3660 3335);
FORCEPROP 2 LASTPIN (-3650 3275) $PN DC38
J 2
(-3660 3285);
DISPLAY 0.617021 (-3660 3285);
PAINT ORANGE (-3660 3285);
FORCEPROP 2 LASTPIN (-3650 3225) $PN DC42
J 2
(-3660 3235);
DISPLAY 0.617021 (-3660 3235);
PAINT ORANGE (-3660 3235);
FORCEPROP 2 LASTPIN (-3650 3175) $PN DC64
J 2
(-3660 3185);
DISPLAY 0.617021 (-3660 3185);
PAINT ORANGE (-3660 3185);
FORCEPROP 2 LASTPIN (-3650 3125) $PN DC66
J 2
(-3660 3135);
DISPLAY 0.617021 (-3660 3135);
PAINT ORANGE (-3660 3135);
FORCEPROP 2 LASTPIN (-3650 3075) $PN DC68
J 2
(-3660 3085);
DISPLAY 0.617021 (-3660 3085);
PAINT ORANGE (-3660 3085);
FORCEPROP 2 LASTPIN (-3650 3025) $PN DC70
J 2
(-3660 3035);
DISPLAY 0.617021 (-3660 3035);
PAINT ORANGE (-3660 3035);
FORCEPROP 2 LASTPIN (-3650 2975) $PN DC78
J 2
(-3660 2985);
DISPLAY 0.617021 (-3660 2985);
PAINT ORANGE (-3660 2985);
FORCEPROP 2 LASTPIN (-3650 2925) $PN DC84
J 2
(-3660 2935);
DISPLAY 0.617021 (-3660 2935);
PAINT ORANGE (-3660 2935);
FORCEPROP 2 LASTPIN (-3650 2875) $PN DC86
J 2
(-3660 2885);
DISPLAY 0.617021 (-3660 2885);
PAINT ORANGE (-3660 2885);
FORCEPROP 2 LASTPIN (-3650 2825) $PN DD11
J 2
(-3660 2835);
DISPLAY 0.617021 (-3660 2835);
PAINT ORANGE (-3660 2835);
FORCEPROP 2 LASTPIN (-3650 2775) $PN DD23
J 2
(-3660 2785);
DISPLAY 0.617021 (-3660 2785);
PAINT ORANGE (-3660 2785);
FORCEPROP 2 LASTPIN (-3650 2725) $PN DD27
J 2
(-3660 2735);
DISPLAY 0.617021 (-3660 2735);
PAINT ORANGE (-3660 2735);
FORCEPROP 2 LASTPIN (-3650 2675) $PN DD31
J 2
(-3660 2685);
DISPLAY 0.617021 (-3660 2685);
PAINT ORANGE (-3660 2685);
FORCEPROP 2 LASTPIN (-3650 2625) $PN DD33
J 2
(-3660 2635);
DISPLAY 0.617021 (-3660 2635);
PAINT ORANGE (-3660 2635);
FORCEPROP 2 LASTPIN (-3650 2575) $PN DD37
J 2
(-3660 2585);
DISPLAY 0.617021 (-3660 2585);
PAINT ORANGE (-3660 2585);
FORCEPROP 2 LASTPIN (-3650 2525) $PN DD71
J 2
(-3660 2535);
DISPLAY 0.617021 (-3660 2535);
PAINT ORANGE (-3660 2535);
FORCEPROP 2 LASTPIN (-3650 2475) $PN DD73
J 2
(-3660 2485);
DISPLAY 0.617021 (-3660 2485);
PAINT ORANGE (-3660 2485);
FORCEPROP 2 LASTPIN (-3650 2425) $PN DD75
J 2
(-3660 2435);
DISPLAY 0.617021 (-3660 2435);
PAINT ORANGE (-3660 2435);
FORCEPROP 2 LASTPIN (-3650 2375) $PN DD81
J 2
(-3660 2385);
DISPLAY 0.617021 (-3660 2385);
PAINT ORANGE (-3660 2385);
FORCEPROP 2 LASTPIN (-3650 2325) $PN DD83
J 2
(-3660 2335);
DISPLAY 0.617021 (-3660 2335);
PAINT ORANGE (-3660 2335);
FORCEPROP 2 LASTPIN (-3650 2275) $PN DE6
J 2
(-3660 2285);
DISPLAY 0.617021 (-3660 2285);
PAINT ORANGE (-3660 2285);
FORCEPROP 2 LASTPIN (-3650 2225) $PN DE8
J 2
(-3660 2235);
DISPLAY 0.617021 (-3660 2235);
PAINT ORANGE (-3660 2235);
FORCEPROP 2 LASTPIN (-3650 2175) $PN DE18
J 2
(-3660 2185);
DISPLAY 0.617021 (-3660 2185);
PAINT ORANGE (-3660 2185);
FORCEPROP 2 LASTPIN (-3650 2125) $PN DE20
J 2
(-3660 2135);
DISPLAY 0.617021 (-3660 2135);
PAINT ORANGE (-3660 2135);
FORCEPROP 2 LASTPIN (-3650 2075) $PN DE24
J 2
(-3660 2085);
DISPLAY 0.617021 (-3660 2085);
PAINT ORANGE (-3660 2085);
FORCEPROP 2 LASTPIN (-3650 2025) $PN DE28
J 2
(-3660 2035);
DISPLAY 0.617021 (-3660 2035);
PAINT ORANGE (-3660 2035);
FORCEPROP 2 LASTPIN (-3650 1975) $PN DE30
J 2
(-3660 1985);
DISPLAY 0.617021 (-3660 1985);
PAINT ORANGE (-3660 1985);
FORCEPROP 2 LASTPIN (-3650 1925) $PN DE34
J 2
(-3660 1935);
DISPLAY 0.617021 (-3660 1935);
PAINT ORANGE (-3660 1935);
FORCEPROP 2 LASTPIN (-3650 1875) $PN DE36
J 2
(-3660 1885);
DISPLAY 0.617021 (-3660 1885);
PAINT ORANGE (-3660 1885);
FORCEPROP 2 LASTPIN (-3650 1825) $PN DE64
J 2
(-3660 1835);
DISPLAY 0.617021 (-3660 1835);
PAINT ORANGE (-3660 1835);
FORCEPROP 2 LASTPIN (-3650 1775) $PN DE70
J 2
(-3660 1785);
DISPLAY 0.617021 (-3660 1785);
PAINT ORANGE (-3660 1785);
FORCEPROP 2 LASTPIN (-3650 1725) $PN DE72
J 2
(-3660 1735);
DISPLAY 0.617021 (-3660 1735);
PAINT ORANGE (-3660 1735);
FORCEPROP 2 LASTPIN (-3650 1675) $PN DE78
J 2
(-3660 1685);
DISPLAY 0.617021 (-3660 1685);
PAINT ORANGE (-3660 1685);
FORCEPROP 2 LASTPIN (-3650 1625) $PN DF5
J 2
(-3660 1635);
DISPLAY 0.617021 (-3660 1635);
PAINT ORANGE (-3660 1635);
FORCEPROP 2 LASTPIN (-3650 1575) $PN DF7
J 2
(-3660 1585);
DISPLAY 0.617021 (-3660 1585);
PAINT ORANGE (-3660 1585);
FORCEPROP 2 LASTPIN (-3650 1525) $PN H51
J 2
(-3660 1535);
DISPLAY 0.617021 (-3660 1535);
PAINT ORANGE (-3660 1535);
FORCEPROP 2 LASTPIN (-3650 1475) $PN DF19
J 2
(-3660 1485);
DISPLAY 0.617021 (-3660 1485);
PAINT ORANGE (-3660 1485);
FORCEPROP 2 LASTPIN (-3650 1425) $PN DF29
J 2
(-3660 1435);
DISPLAY 0.617021 (-3660 1435);
PAINT ORANGE (-3660 1435);
FORCEPROP 2 LASTPIN (-3650 1375) $PN DF35
J 2
(-3660 1385);
DISPLAY 0.617021 (-3660 1385);
PAINT ORANGE (-3660 1385);
FORCEPROP 2 LASTPIN (-3650 1325) $PN DF37
J 2
(-3660 1335);
DISPLAY 0.617021 (-3660 1335);
PAINT ORANGE (-3660 1335);
FORCEPROP 2 LASTPIN (-3650 1275) $PN DF39
J 2
(-3660 1285);
DISPLAY 0.617021 (-3660 1285);
PAINT ORANGE (-3660 1285);
FORCEPROP 2 LASTPIN (-3650 1225) $PN DF41
J 2
(-3660 1235);
DISPLAY 0.617021 (-3660 1235);
PAINT ORANGE (-3660 1235);
FORCEPROP 2 LASTPIN (-3650 1175) $PN DF65
J 2
(-3660 1185);
DISPLAY 0.617021 (-3660 1185);
PAINT ORANGE (-3660 1185);
FORCEPROP 2 LASTPIN (-3650 1125) $PN DF69
J 2
(-3660 1135);
DISPLAY 0.617021 (-3660 1135);
PAINT ORANGE (-3660 1135);
FORCEPROP 2 LASTPIN (-3650 1075) $PN DF73
J 2
(-3660 1085);
DISPLAY 0.617021 (-3660 1085);
PAINT ORANGE (-3660 1085);
FORCEPROP 2 LASTPIN (-3650 1025) $PN DF79
J 2
(-3660 1035);
DISPLAY 0.617021 (-3660 1035);
PAINT ORANGE (-3660 1035);
FORCEPROP 2 LASTPIN (-3650 975) $PN DF83
J 2
(-3660 985);
DISPLAY 0.617021 (-3660 985);
PAINT ORANGE (-3660 985);
FORCEPROP 2 LASTPIN (-3650 925) $PN DF85
J 2
(-3660 935);
DISPLAY 0.617021 (-3660 935);
PAINT ORANGE (-3660 935);
FORCEPROP 2 LASTPIN (-3650 875) $PN DG2
J 2
(-3660 885);
DISPLAY 0.617021 (-3660 885);
PAINT ORANGE (-3660 885);
FORCEPROP 2 LASTPIN (-3650 825) $PN H49
J 2
(-3660 835);
DISPLAY 0.617021 (-3660 835);
PAINT ORANGE (-3660 835);
FORCEPROP 2 LASTPIN (-3650 775) $PN DG14
J 2
(-3660 785);
DISPLAY 0.617021 (-3660 785);
PAINT ORANGE (-3660 785);
FORCEPROP 2 LASTPIN (-3650 725) $PN DG16
J 2
(-3660 735);
DISPLAY 0.617021 (-3660 735);
PAINT ORANGE (-3660 735);
FORCEPROP 2 LASTPIN (-3650 675) $PN DG24
J 2
(-3660 685);
DISPLAY 0.617021 (-3660 685);
PAINT ORANGE (-3660 685);
FORCEPROP 2 LASTPIN (-3650 625) $PN DG66
J 2
(-3660 635);
DISPLAY 0.617021 (-3660 635);
PAINT ORANGE (-3660 635);
FORCEPROP 2 LASTPIN (-3650 575) $PN DG68
J 2
(-3660 585);
DISPLAY 0.617021 (-3660 585);
PAINT ORANGE (-3660 585);
FORCEPROP 2 LASTPIN (-2450 4525) $PN DG76
J 0
(-2440 4535);
DISPLAY 0.617021 (-2440 4535);
PAINT ORANGE (-2440 4535);
FORCEPROP 2 LASTPIN (-2450 4425) $PN DG80
J 0
(-2440 4435);
DISPLAY 0.617021 (-2440 4435);
PAINT ORANGE (-2440 4435);
FORCEPROP 2 LASTPIN (-2450 4375) $PN DG82
J 0
(-2440 4385);
DISPLAY 0.617021 (-2440 4385);
PAINT ORANGE (-2440 4385);
FORCEPROP 2 LASTPIN (-2450 4325) $PN DH13
J 0
(-2440 4335);
DISPLAY 0.617021 (-2440 4335);
PAINT ORANGE (-2440 4335);
FORCEPROP 2 LASTPIN (-2450 4275) $PN DH15
J 0
(-2440 4285);
DISPLAY 0.617021 (-2440 4285);
PAINT ORANGE (-2440 4285);
FORCEPROP 2 LASTPIN (-2450 4225) $PN DH23
J 0
(-2440 4235);
DISPLAY 0.617021 (-2440 4235);
PAINT ORANGE (-2440 4235);
FORCEPROP 2 LASTPIN (-2450 4175) $PN DH25
J 0
(-2440 4185);
DISPLAY 0.617021 (-2440 4185);
PAINT ORANGE (-2440 4185);
FORCEPROP 2 LASTPIN (-2450 4125) $PN DH27
J 0
(-2440 4135);
DISPLAY 0.617021 (-2440 4135);
PAINT ORANGE (-2440 4135);
FORCEPROP 2 LASTPIN (-2450 4075) $PN DH29
J 0
(-2440 4085);
DISPLAY 0.617021 (-2440 4085);
PAINT ORANGE (-2440 4085);
FORCEPROP 2 LASTPIN (-2450 4025) $PN DH31
J 0
(-2440 4035);
DISPLAY 0.617021 (-2440 4035);
PAINT ORANGE (-2440 4035);
FORCEPROP 2 LASTPIN (-2450 3975) $PN DH33
J 0
(-2440 3985);
DISPLAY 0.617021 (-2440 3985);
PAINT ORANGE (-2440 3985);
FORCEPROP 2 LASTPIN (-2450 3925) $PN DH35
J 0
(-2440 3935);
DISPLAY 0.617021 (-2440 3935);
PAINT ORANGE (-2440 3935);
FORCEPROP 2 LASTPIN (-2450 3875) $PN DH37
J 0
(-2440 3885);
DISPLAY 0.617021 (-2440 3885);
PAINT ORANGE (-2440 3885);
FORCEPROP 2 LASTPIN (-2450 3825) $PN DH41
J 0
(-2440 3835);
DISPLAY 0.617021 (-2440 3835);
PAINT ORANGE (-2440 3835);
FORCEPROP 2 LASTPIN (-2450 3775) $PN DH67
J 0
(-2440 3785);
DISPLAY 0.617021 (-2440 3785);
PAINT ORANGE (-2440 3785);
FORCEPROP 2 LASTPIN (-2450 3725) $PN DH71
J 0
(-2440 3735);
DISPLAY 0.617021 (-2440 3735);
PAINT ORANGE (-2440 3735);
FORCEPROP 2 LASTPIN (-2450 3675) $PN DH73
J 0
(-2440 3685);
DISPLAY 0.617021 (-2440 3685);
PAINT ORANGE (-2440 3685);
FORCEPROP 2 LASTPIN (-2450 3575) $PN DH81
J 0
(-2440 3585);
DISPLAY 0.617021 (-2440 3585);
PAINT ORANGE (-2440 3585);
FORCEPROP 2 LASTPIN (-2450 3525) $PN DH83
J 0
(-2440 3535);
DISPLAY 0.617021 (-2440 3535);
PAINT ORANGE (-2440 3535);
FORCEPROP 2 LASTPIN (-2450 3475) $PN DJ2
J 0
(-2440 3485);
DISPLAY 0.617021 (-2440 3485);
PAINT ORANGE (-2440 3485);
FORCEPROP 2 LASTPIN (-2450 3425) $PN DJ10
J 0
(-2440 3435);
DISPLAY 0.617021 (-2440 3435);
PAINT ORANGE (-2440 3435);
FORCEPROP 2 LASTPIN (-2450 3375) $PN H47
J 0
(-2440 3385);
DISPLAY 0.617021 (-2440 3385);
PAINT ORANGE (-2440 3385);
FORCEPROP 2 LASTPIN (-2450 3325) $PN DJ22
J 0
(-2440 3335);
DISPLAY 0.617021 (-2440 3335);
PAINT ORANGE (-2440 3335);
FORCEPROP 2 LASTPIN (-2450 3275) $PN DJ38
J 0
(-2440 3285);
DISPLAY 0.617021 (-2440 3285);
PAINT ORANGE (-2440 3285);
FORCEPROP 2 LASTPIN (-2450 3225) $PN DJ42
J 0
(-2440 3235);
DISPLAY 0.617021 (-2440 3235);
PAINT ORANGE (-2440 3235);
FORCEPROP 2 LASTPIN (-2450 3175) $PN DJ68
J 0
(-2440 3185);
DISPLAY 0.617021 (-2440 3185);
PAINT ORANGE (-2440 3185);
FORCEPROP 2 LASTPIN (-2450 3125) $PN DJ74
J 0
(-2440 3135);
DISPLAY 0.617021 (-2440 3135);
PAINT ORANGE (-2440 3135);
FORCEPROP 2 LASTPIN (-2450 3075) $PN DJ78
J 0
(-2440 3085);
DISPLAY 0.617021 (-2440 3085);
PAINT ORANGE (-2440 3085);
FORCEPROP 2 LASTPIN (-2450 3025) $PN DJ82
J 0
(-2440 3035);
DISPLAY 0.617021 (-2440 3035);
PAINT ORANGE (-2440 3035);
FORCEPROP 2 LASTPIN (-2450 2975) $PN DJ84
J 0
(-2440 2985);
DISPLAY 0.617021 (-2440 2985);
PAINT ORANGE (-2440 2985);
FORCEPROP 2 LASTPIN (-2450 2925) $PN DK7
J 0
(-2440 2935);
DISPLAY 0.617021 (-2440 2935);
PAINT ORANGE (-2440 2935);
FORCEPROP 2 LASTPIN (-2450 2875) $PN DK23
J 0
(-2440 2885);
DISPLAY 0.617021 (-2440 2885);
PAINT ORANGE (-2440 2885);
FORCEPROP 2 LASTPIN (-2450 2825) $PN DK29
J 0
(-2440 2835);
DISPLAY 0.617021 (-2440 2835);
PAINT ORANGE (-2440 2835);
FORCEPROP 2 LASTPIN (-2450 2775) $PN DK35
J 0
(-2440 2785);
DISPLAY 0.617021 (-2440 2785);
PAINT ORANGE (-2440 2785);
FORCEPROP 2 LASTPIN (-2450 2725) $PN DK39
J 0
(-2440 2735);
DISPLAY 0.617021 (-2440 2735);
PAINT ORANGE (-2440 2735);
FORCEPROP 2 LASTPIN (-2450 2675) $PN DK41
J 0
(-2440 2685);
DISPLAY 0.617021 (-2440 2685);
PAINT ORANGE (-2440 2685);
FORCEPROP 2 LASTPIN (-2450 2625) $PN DK73
J 0
(-2440 2635);
DISPLAY 0.617021 (-2440 2635);
PAINT ORANGE (-2440 2635);
FORCEPROP 2 LASTPIN (-2450 2575) $PN DK75
J 0
(-2440 2585);
DISPLAY 0.617021 (-2440 2585);
PAINT ORANGE (-2440 2585);
FORCEPROP 2 LASTPIN (-2450 2525) $PN DK77
J 0
(-2440 2535);
DISPLAY 0.617021 (-2440 2535);
PAINT ORANGE (-2440 2535);
FORCEPROP 2 LASTPIN (-2450 2475) $PN DK83
J 0
(-2440 2485);
DISPLAY 0.617021 (-2440 2485);
PAINT ORANGE (-2440 2485);
FORCEPROP 2 LASTPIN (-2450 2425) $PN DK85
J 0
(-2440 2435);
DISPLAY 0.617021 (-2440 2435);
PAINT ORANGE (-2440 2435);
FORCEPROP 2 LASTPIN (-2450 2375) $PN DL16
J 0
(-2440 2385);
DISPLAY 0.617021 (-2440 2385);
PAINT ORANGE (-2440 2385);
FORCEPROP 2 LASTPIN (-2450 2325) $PN DL18
J 0
(-2440 2335);
DISPLAY 0.617021 (-2440 2335);
PAINT ORANGE (-2440 2335);
FORCEPROP 2 LASTPIN (-2450 2275) $PN DL4
J 0
(-2440 2285);
DISPLAY 0.617021 (-2440 2285);
PAINT ORANGE (-2440 2285);
FORCEPROP 2 LASTPIN (-2450 2225) $PN DL22
J 0
(-2440 2235);
DISPLAY 0.617021 (-2440 2235);
PAINT ORANGE (-2440 2235);
FORCEPROP 2 LASTPIN (-2450 2175) $PN DL24
J 0
(-2440 2185);
DISPLAY 0.617021 (-2440 2185);
PAINT ORANGE (-2440 2185);
FORCEPROP 2 LASTPIN (-2450 2125) $PN DL28
J 0
(-2440 2135);
DISPLAY 0.617021 (-2440 2135);
PAINT ORANGE (-2440 2135);
FORCEPROP 2 LASTPIN (-2450 2075) $PN DL30
J 0
(-2440 2085);
DISPLAY 0.617021 (-2440 2085);
PAINT ORANGE (-2440 2085);
FORCEPROP 2 LASTPIN (-2450 2025) $PN DL34
J 0
(-2440 2035);
DISPLAY 0.617021 (-2440 2035);
PAINT ORANGE (-2440 2035);
FORCEPROP 2 LASTPIN (-2450 1975) $PN DL36
J 0
(-2440 1985);
DISPLAY 0.617021 (-2440 1985);
PAINT ORANGE (-2440 1985);
FORCEPROP 2 LASTPIN (-2450 1925) $PN DL40
J 0
(-2440 1935);
DISPLAY 0.617021 (-2440 1935);
PAINT ORANGE (-2440 1935);
FORCEPROP 2 LASTPIN (-2450 1875) $PN DL68
J 0
(-2440 1885);
DISPLAY 0.617021 (-2440 1885);
PAINT ORANGE (-2440 1885);
FORCEPROP 2 LASTPIN (-2450 1825) $PN DL70
J 0
(-2440 1835);
DISPLAY 0.617021 (-2440 1835);
PAINT ORANGE (-2440 1835);
FORCEPROP 2 LASTPIN (-2450 1775) $PN DL74
J 0
(-2440 1785);
DISPLAY 0.617021 (-2440 1785);
PAINT ORANGE (-2440 1785);
FORCEPROP 2 LASTPIN (-2450 1725) $PN DL76
J 0
(-2440 1735);
DISPLAY 0.617021 (-2440 1735);
PAINT ORANGE (-2440 1735);
FORCEPROP 2 LASTPIN (-2450 1675) $PN DL78
J 0
(-2440 1685);
DISPLAY 0.617021 (-2440 1685);
PAINT ORANGE (-2440 1685);
FORCEPROP 2 LASTPIN (-2450 1625) $PN DL80
J 0
(-2440 1635);
DISPLAY 0.617021 (-2440 1635);
PAINT ORANGE (-2440 1635);
FORCEPROP 2 LASTPIN (-2450 1575) $PN DM15
J 0
(-2440 1585);
DISPLAY 0.617021 (-2440 1585);
PAINT ORANGE (-2440 1585);
FORCEPROP 2 LASTPIN (-2450 1525) $PN H45
J 0
(-2440 1535);
DISPLAY 0.617021 (-2440 1535);
PAINT ORANGE (-2440 1535);
FORCEPROP 2 LASTPIN (-2450 1475) $PN DM25
J 0
(-2440 1485);
DISPLAY 0.617021 (-2440 1485);
PAINT ORANGE (-2440 1485);
FORCEPROP 2 LASTPIN (-2450 1425) $PN DM27
J 0
(-2440 1435);
DISPLAY 0.617021 (-2440 1435);
PAINT ORANGE (-2440 1435);
FORCEPROP 2 LASTPIN (-2450 1375) $PN DM31
J 0
(-2440 1385);
DISPLAY 0.617021 (-2440 1385);
PAINT ORANGE (-2440 1385);
FORCEPROP 2 LASTPIN (-2450 1325) $PN DM33
J 0
(-2440 1335);
DISPLAY 0.617021 (-2440 1335);
PAINT ORANGE (-2440 1335);
FORCEPROP 2 LASTPIN (-2450 1275) $PN DM37
J 0
(-2440 1285);
DISPLAY 0.617021 (-2440 1285);
PAINT ORANGE (-2440 1285);
FORCEPROP 2 LASTPIN (-2450 1225) $PN DM39
J 0
(-2440 1235);
DISPLAY 0.617021 (-2440 1235);
PAINT ORANGE (-2440 1235);
FORCEPROP 2 LASTPIN (-2450 1175) $PN DM65
J 0
(-2440 1185);
DISPLAY 0.617021 (-2440 1185);
PAINT ORANGE (-2440 1185);
FORCEPROP 2 LASTPIN (-2450 1125) $PN DM73
J 0
(-2440 1135);
DISPLAY 0.617021 (-2440 1135);
PAINT ORANGE (-2440 1135);
FORCEPROP 2 LASTPIN (-2450 1075) $PN DM77
J 0
(-2440 1085);
DISPLAY 0.617021 (-2440 1085);
PAINT ORANGE (-2440 1085);
FORCEPROP 2 LASTPIN (-2450 1025) $PN DM83
J 0
(-2440 1035);
DISPLAY 0.617021 (-2440 1035);
PAINT ORANGE (-2440 1035);
FORCEPROP 2 LASTPIN (-2450 975) $PN DN2
J 0
(-2440 985);
DISPLAY 0.617021 (-2440 985);
PAINT ORANGE (-2440 985);
FORCEPROP 2 LASTPIN (-2450 925) $PN BH17
J 0
(-2440 935);
DISPLAY 0.617021 (-2440 935);
PAINT ORANGE (-2440 935);
FORCEPROP 2 LASTPIN (-2450 875) $PN DN12
J 0
(-2440 885);
DISPLAY 0.617021 (-2440 885);
PAINT ORANGE (-2440 885);
FORCEPROP 2 LASTPIN (-2450 825) $PN DN22
J 0
(-2440 835);
DISPLAY 0.617021 (-2440 835);
PAINT ORANGE (-2440 835);
FORCEPROP 2 LASTPIN (-2450 775) $PN DN26
J 0
(-2440 785);
DISPLAY 0.617021 (-2440 785);
PAINT ORANGE (-2440 785);
FORCEPROP 2 LASTPIN (-2450 725) $PN DN32
J 0
(-2440 735);
DISPLAY 0.617021 (-2440 735);
PAINT ORANGE (-2440 735);
FORCEPROP 2 LASTPIN (-2450 675) $PN DN38
J 0
(-2440 685);
DISPLAY 0.617021 (-2440 685);
PAINT ORANGE (-2440 685);
FORCEPROP 2 LASTPIN (-2450 625) $PN DN68
J 0
(-2440 635);
DISPLAY 0.617021 (-2440 635);
PAINT ORANGE (-2440 635);
FORCEPROP 2 LASTPIN (-2450 575) $PN DN72
J 0
(-2440 585);
DISPLAY 0.617021 (-2440 585);
PAINT ORANGE (-2440 585);
FORCEPROP 2 LASTPIN (-2450 3625) $PN DH79
J 0
(-2440 3635);
DISPLAY 0.617021 (-2440 3635);
PAINT ORANGE (-2440 3635);
FORCEPROP 2 LASTPIN (-2450 4475) $PN DG78
J 0
(-2440 4485);
DISPLAY 0.617021 (-2440 4485);
PAINT ORANGE (-2440 4485);
FORCEPROP 1 LAST PACK_TYPE BGA1
J 0
(-3600 4825);
PAINT SKYBLUE (-3600 4825);
DISPLAY INVISIBLE (-3600 4825);
FORCEPROP 2 LAST SEC_TYPE BGA1
J 0
(-3600 4825);
DISPLAY 1.021277 (-3600 4825);
PAINT ORANGE (-3600 4825);
DISPLAY INVISIBLE (-3600 4825);
FORCEPROP 2 LAST CDS_LIB chpset_lib
J 0
(-3050 2525);
PAINT ORANGE (-3050 2525);
DISPLAY INVISIBLE (-3050 2525);
FORCEPROP 2 LAST SEC 29
J 0
(-3600 4825);
DISPLAY 0.680851 (-3600 4825);
PAINT MONO (-3600 4825);
DISPLAY INVISIBLE (-3600 4825);
FORCEPROP 2 LAST CDS_LOCATION U2D1
J 0
(-3600 4775);
DISPLAY 0.617021 (-3600 4775);
PAINT AQUA (-3600 4775);
DISPLAY INVISIBLE (-3600 4775);
FORCEPROP 1 LAST PATH I19
J 0
(-3050 4725);
PAINT GREEN (-3050 4725);
DISPLAY INVISIBLE (-3050 4725);
FORCEADD SKX_EXT_B..30
(-1225 2550);
FORCEPROP 1 LAST LOCATION U2D1
J 0
(-1775 4800);
DISPLAY 0.617021 (-1775 4800);
PAINT AQUA (-1775 4800);
FORCEPROP 1 LAST PART_NUMBER TBD
J 0
(-1775 400);
DISPLAY 0.617021 (-1775 400);
PAINT BLUE (-1775 400);
FORCEPROP 1 LAST MATERIAL IC
J 0
(-1775 4750);
DISPLAY 0.617021 (-1775 4750);
PAINT SKYBLUE (-1775 4750);
FORCEPROP 2 LASTPIN (-1825 4550) $PN DN78
J 2
(-1835 4560);
DISPLAY 0.617021 (-1835 4560);
PAINT ORANGE (-1835 4560);
FORCEPROP 2 LASTPIN (-1825 4500) $PN DP67
J 2
(-1835 4510);
DISPLAY 0.617021 (-1835 4510);
PAINT ORANGE (-1835 4510);
FORCEPROP 2 LASTPIN (-1825 4450) $PN DP69
J 2
(-1835 4460);
DISPLAY 0.617021 (-1835 4460);
PAINT ORANGE (-1835 4460);
FORCEPROP 2 LASTPIN (-1825 4400) $PN DP71
J 2
(-1835 4410);
DISPLAY 0.617021 (-1835 4410);
PAINT ORANGE (-1835 4410);
FORCEPROP 2 LASTPIN (-1825 4350) $PN DP81
J 2
(-1835 4360);
DISPLAY 0.617021 (-1835 4360);
PAINT ORANGE (-1835 4360);
FORCEPROP 2 LASTPIN (-1825 4300) $PN DP83
J 2
(-1835 4310);
DISPLAY 0.617021 (-1835 4310);
PAINT ORANGE (-1835 4310);
FORCEPROP 2 LASTPIN (-1825 4250) $PN BR26
J 2
(-1835 4260);
DISPLAY 0.617021 (-1835 4260);
PAINT ORANGE (-1835 4260);
FORCEPROP 2 LASTPIN (-1825 4200) $PN DR6
J 2
(-1835 4210);
DISPLAY 0.617021 (-1835 4210);
PAINT ORANGE (-1835 4210);
FORCEPROP 2 LASTPIN (-1825 4150) $PN CA20
J 2
(-1835 4160);
DISPLAY 0.617021 (-1835 4160);
PAINT ORANGE (-1835 4160);
FORCEPROP 2 LASTPIN (-1825 4100) $PN CL22
J 2
(-1835 4110);
DISPLAY 0.617021 (-1835 4110);
PAINT ORANGE (-1835 4110);
FORCEPROP 2 LASTPIN (-1825 4050) $PN DR20
J 2
(-1835 4060);
DISPLAY 0.617021 (-1835 4060);
PAINT ORANGE (-1835 4060);
FORCEPROP 2 LASTPIN (-1825 4000) $PN DR22
J 2
(-1835 4010);
DISPLAY 0.617021 (-1835 4010);
PAINT ORANGE (-1835 4010);
FORCEPROP 2 LASTPIN (-1825 3950) $PN DR24
J 2
(-1835 3960);
DISPLAY 0.617021 (-1835 3960);
PAINT ORANGE (-1835 3960);
FORCEPROP 2 LASTPIN (-1825 3900) $PN DR26
J 2
(-1835 3910);
DISPLAY 0.617021 (-1835 3910);
PAINT ORANGE (-1835 3910);
FORCEPROP 2 LASTPIN (-1825 3850) $PN DR28
J 2
(-1835 3860);
DISPLAY 0.617021 (-1835 3860);
PAINT ORANGE (-1835 3860);
FORCEPROP 2 LASTPIN (-1825 3800) $PN DR30
J 2
(-1835 3810);
DISPLAY 0.617021 (-1835 3810);
PAINT ORANGE (-1835 3810);
FORCEPROP 2 LASTPIN (-1825 3750) $PN DR32
J 2
(-1835 3760);
DISPLAY 0.617021 (-1835 3760);
PAINT ORANGE (-1835 3760);
FORCEPROP 2 LASTPIN (-1825 3700) $PN DR34
J 2
(-1835 3710);
DISPLAY 0.617021 (-1835 3710);
PAINT ORANGE (-1835 3710);
FORCEPROP 2 LASTPIN (-1825 3650) $PN DR36
J 2
(-1835 3660);
DISPLAY 0.617021 (-1835 3660);
PAINT ORANGE (-1835 3660);
FORCEPROP 2 LASTPIN (-1825 3600) $PN DR38
J 2
(-1835 3610);
DISPLAY 0.617021 (-1835 3610);
PAINT ORANGE (-1835 3610);
FORCEPROP 2 LASTPIN (-1825 3550) $PN DR40
J 2
(-1835 3560);
DISPLAY 0.617021 (-1835 3560);
PAINT ORANGE (-1835 3560);
FORCEPROP 2 LASTPIN (-1825 3500) $PN DR42
J 2
(-1835 3510);
DISPLAY 0.617021 (-1835 3510);
PAINT ORANGE (-1835 3510);
FORCEPROP 2 LASTPIN (-1825 3450) $PN DR66
J 2
(-1835 3460);
DISPLAY 0.617021 (-1835 3460);
PAINT ORANGE (-1835 3460);
FORCEPROP 2 LASTPIN (-1825 3400) $PN DR68
J 2
(-1835 3410);
DISPLAY 0.617021 (-1835 3410);
PAINT ORANGE (-1835 3410);
FORCEPROP 2 LASTPIN (-1825 3350) $PN DR70
J 2
(-1835 3360);
DISPLAY 0.617021 (-1835 3360);
PAINT ORANGE (-1835 3360);
FORCEPROP 2 LASTPIN (-1825 3300) $PN DR72
J 2
(-1835 3310);
DISPLAY 0.617021 (-1835 3310);
PAINT ORANGE (-1835 3310);
FORCEPROP 2 LASTPIN (-1825 3250) $PN DR74
J 2
(-1835 3260);
DISPLAY 0.617021 (-1835 3260);
PAINT ORANGE (-1835 3260);
FORCEPROP 2 LASTPIN (-1825 3200) $PN DR76
J 2
(-1835 3210);
DISPLAY 0.617021 (-1835 3210);
PAINT ORANGE (-1835 3210);
FORCEPROP 2 LASTPIN (-1825 3150) $PN DR78
J 2
(-1835 3160);
DISPLAY 0.617021 (-1835 3160);
PAINT ORANGE (-1835 3160);
FORCEPROP 2 LASTPIN (-1825 3100) $PN DT3
J 2
(-1835 3110);
DISPLAY 0.617021 (-1835 3110);
PAINT ORANGE (-1835 3110);
FORCEPROP 2 LASTPIN (-1825 3050) $PN DT17
J 2
(-1835 3060);
DISPLAY 0.617021 (-1835 3060);
PAINT ORANGE (-1835 3060);
FORCEPROP 2 LASTPIN (-1825 3000) $PN DH21
J 2
(-1835 3010);
DISPLAY 0.617021 (-1835 3010);
PAINT ORANGE (-1835 3010);
FORCEPROP 2 LASTPIN (-1825 2950) $PN DT65
J 2
(-1835 2960);
DISPLAY 0.617021 (-1835 2960);
PAINT ORANGE (-1835 2960);
FORCEPROP 2 LASTPIN (-1825 2900) $PN DT69
J 2
(-1835 2910);
DISPLAY 0.617021 (-1835 2910);
PAINT ORANGE (-1835 2910);
FORCEPROP 2 LASTPIN (-1825 2850) $PN DT79
J 2
(-1835 2860);
DISPLAY 0.617021 (-1835 2860);
PAINT ORANGE (-1835 2860);
FORCEPROP 2 LASTPIN (-1825 2800) $PN DT83
J 2
(-1835 2810);
DISPLAY 0.617021 (-1835 2810);
PAINT ORANGE (-1835 2810);
FORCEPROP 2 LASTPIN (-1825 2750) $PN DT85
J 2
(-1835 2760);
DISPLAY 0.617021 (-1835 2760);
PAINT ORANGE (-1835 2760);
FORCEPROP 2 LASTPIN (-1825 2700) $PN DU10
J 2
(-1835 2710);
DISPLAY 0.617021 (-1835 2710);
PAINT ORANGE (-1835 2710);
FORCEPROP 2 LASTPIN (-1825 2650) $PN DU14
J 2
(-1835 2660);
DISPLAY 0.617021 (-1835 2660);
PAINT ORANGE (-1835 2660);
FORCEPROP 2 LASTPIN (-1825 2600) $PN CN14
J 2
(-1835 2610);
DISPLAY 0.617021 (-1835 2610);
PAINT ORANGE (-1835 2610);
FORCEPROP 2 LASTPIN (-1825 2500) $PN DU26
J 2
(-1835 2510);
DISPLAY 0.617021 (-1835 2510);
PAINT ORANGE (-1835 2510);
FORCEPROP 2 LASTPIN (-1825 2450) $PN DU32
J 2
(-1835 2460);
DISPLAY 0.617021 (-1835 2460);
PAINT ORANGE (-1835 2460);
FORCEPROP 2 LASTPIN (-1825 2400) $PN DU38
J 2
(-1835 2410);
DISPLAY 0.617021 (-1835 2410);
PAINT ORANGE (-1835 2410);
FORCEPROP 2 LASTPIN (-1825 2350) $PN DU70
J 2
(-1835 2360);
DISPLAY 0.617021 (-1835 2360);
PAINT ORANGE (-1835 2360);
FORCEPROP 2 LASTPIN (-1825 2300) $PN DU72
J 2
(-1835 2310);
DISPLAY 0.617021 (-1835 2310);
PAINT ORANGE (-1835 2310);
FORCEPROP 2 LASTPIN (-1825 2250) $PN DU78
J 2
(-1835 2260);
DISPLAY 0.617021 (-1835 2260);
PAINT ORANGE (-1835 2260);
FORCEPROP 2 LASTPIN (-1825 2150) $PN DU82
J 2
(-1835 2160);
DISPLAY 0.617021 (-1835 2160);
PAINT ORANGE (-1835 2160);
FORCEPROP 2 LASTPIN (-1825 2100) $PN DU84
J 2
(-1835 2110);
DISPLAY 0.617021 (-1835 2110);
PAINT ORANGE (-1835 2110);
FORCEPROP 2 LASTPIN (-1825 2050) $PN DV21
J 2
(-1835 2060);
DISPLAY 0.617021 (-1835 2060);
PAINT ORANGE (-1835 2060);
FORCEPROP 2 LASTPIN (-1825 2000) $PN DV25
J 2
(-1835 2010);
DISPLAY 0.617021 (-1835 2010);
PAINT ORANGE (-1835 2010);
FORCEPROP 2 LASTPIN (-1825 1950) $PN DV27
J 2
(-1835 1960);
DISPLAY 0.617021 (-1835 1960);
PAINT ORANGE (-1835 1960);
FORCEPROP 2 LASTPIN (-1825 1900) $PN DV31
J 2
(-1835 1910);
DISPLAY 0.617021 (-1835 1910);
PAINT ORANGE (-1835 1910);
FORCEPROP 2 LASTPIN (-1825 1850) $PN DV33
J 2
(-1835 1860);
DISPLAY 0.617021 (-1835 1860);
PAINT ORANGE (-1835 1860);
FORCEPROP 2 LASTPIN (-1825 1800) $PN DV37
J 2
(-1835 1810);
DISPLAY 0.617021 (-1835 1810);
PAINT ORANGE (-1835 1810);
FORCEPROP 2 LASTPIN (-1825 1750) $PN DV39
J 2
(-1835 1760);
DISPLAY 0.617021 (-1835 1760);
PAINT ORANGE (-1835 1760);
FORCEPROP 2 LASTPIN (-1825 1700) $PN DV73
J 2
(-1835 1710);
DISPLAY 0.617021 (-1835 1710);
PAINT ORANGE (-1835 1710);
FORCEPROP 2 LASTPIN (-1825 1650) $PN DV77
J 2
(-1835 1660);
DISPLAY 0.617021 (-1835 1660);
PAINT ORANGE (-1835 1660);
FORCEPROP 2 LASTPIN (-1825 1600) $PN DV81
J 2
(-1835 1610);
DISPLAY 0.617021 (-1835 1610);
PAINT ORANGE (-1835 1610);
FORCEPROP 2 LASTPIN (-1825 1550) $PN DW12
J 2
(-1835 1560);
DISPLAY 0.617021 (-1835 1560);
PAINT ORANGE (-1835 1560);
FORCEPROP 2 LASTPIN (-1825 1500) $PN DW20
J 2
(-1835 1510);
DISPLAY 0.617021 (-1835 1510);
PAINT ORANGE (-1835 1510);
FORCEPROP 2 LASTPIN (-1825 1450) $PN DW24
J 2
(-1835 1460);
DISPLAY 0.617021 (-1835 1460);
PAINT ORANGE (-1835 1460);
FORCEPROP 2 LASTPIN (-1825 1400) $PN DW28
J 2
(-1835 1410);
DISPLAY 0.617021 (-1835 1410);
PAINT ORANGE (-1835 1410);
FORCEPROP 2 LASTPIN (-1825 1350) $PN DW30
J 2
(-1835 1360);
DISPLAY 0.617021 (-1835 1360);
PAINT ORANGE (-1835 1360);
FORCEPROP 2 LASTPIN (-1825 1300) $PN DW34
J 2
(-1835 1310);
DISPLAY 0.617021 (-1835 1310);
PAINT ORANGE (-1835 1310);
FORCEPROP 2 LASTPIN (-1825 1250) $PN DW36
J 2
(-1835 1260);
DISPLAY 0.617021 (-1835 1260);
PAINT ORANGE (-1835 1260);
FORCEPROP 2 LASTPIN (-1825 1200) $PN DW40
J 2
(-1835 1210);
DISPLAY 0.617021 (-1835 1210);
PAINT ORANGE (-1835 1210);
FORCEPROP 2 LASTPIN (-1825 1150) $PN DW64
J 2
(-1835 1160);
DISPLAY 0.617021 (-1835 1160);
PAINT ORANGE (-1835 1160);
FORCEPROP 2 LASTPIN (-1825 1100) $PN DW66
J 2
(-1835 1110);
DISPLAY 0.617021 (-1835 1110);
PAINT ORANGE (-1835 1110);
FORCEPROP 2 LASTPIN (-1825 1050) $PN DW68
J 2
(-1835 1060);
DISPLAY 0.617021 (-1835 1060);
PAINT ORANGE (-1835 1060);
FORCEPROP 2 LASTPIN (-1825 1000) $PN DW70
J 2
(-1835 1010);
DISPLAY 0.617021 (-1835 1010);
PAINT ORANGE (-1835 1010);
FORCEPROP 2 LASTPIN (-1825 950) $PN DW72
J 2
(-1835 960);
DISPLAY 0.617021 (-1835 960);
PAINT ORANGE (-1835 960);
FORCEPROP 2 LASTPIN (-1825 900) $PN DW74
J 2
(-1835 910);
DISPLAY 0.617021 (-1835 910);
PAINT ORANGE (-1835 910);
FORCEPROP 2 LASTPIN (-1825 850) $PN DW76
J 2
(-1835 860);
DISPLAY 0.617021 (-1835 860);
PAINT ORANGE (-1835 860);
FORCEPROP 2 LASTPIN (-1825 800) $PN DW8
J 2
(-1835 810);
DISPLAY 0.617021 (-1835 810);
PAINT ORANGE (-1835 810);
FORCEPROP 2 LASTPIN (-1825 750) $PN DW82
J 2
(-1835 760);
DISPLAY 0.617021 (-1835 760);
PAINT ORANGE (-1835 760);
FORCEPROP 2 LASTPIN (-1825 700) $PN DW84
J 2
(-1835 710);
DISPLAY 0.617021 (-1835 710);
PAINT ORANGE (-1835 710);
FORCEPROP 2 LASTPIN (-1825 650) $PN DY5
J 2
(-1835 660);
DISPLAY 0.617021 (-1835 660);
PAINT ORANGE (-1835 660);
FORCEPROP 2 LASTPIN (-1825 600) $PN DY19
J 2
(-1835 610);
DISPLAY 0.617021 (-1835 610);
PAINT ORANGE (-1835 610);
FORCEPROP 2 LASTPIN (-625 4550) $PN DY23
J 0
(-615 4560);
DISPLAY 0.617021 (-615 4560);
PAINT ORANGE (-615 4560);
FORCEPROP 2 LASTPIN (-625 4500) $PN DY29
J 0
(-615 4510);
DISPLAY 0.617021 (-615 4510);
PAINT ORANGE (-615 4510);
FORCEPROP 2 LASTPIN (-625 4450) $PN DY35
J 0
(-615 4460);
DISPLAY 0.617021 (-615 4460);
PAINT ORANGE (-615 4460);
FORCEPROP 2 LASTPIN (-625 4400) $PN DY41
J 0
(-615 4410);
DISPLAY 0.617021 (-615 4410);
PAINT ORANGE (-615 4410);
FORCEPROP 2 LASTPIN (-625 4350) $PN DY71
J 0
(-615 4360);
DISPLAY 0.617021 (-615 4360);
PAINT ORANGE (-615 4360);
FORCEPROP 2 LASTPIN (-625 4300) $PN DY75
J 0
(-615 4310);
DISPLAY 0.617021 (-615 4310);
PAINT ORANGE (-615 4310);
FORCEPROP 2 LASTPIN (-625 4250) $PN EA6
J 0
(-615 4260);
DISPLAY 0.617021 (-615 4260);
PAINT ORANGE (-615 4260);
FORCEPROP 2 LASTPIN (-625 4200) $PN J16
J 0
(-615 4210);
DISPLAY 0.617021 (-615 4210);
PAINT ORANGE (-615 4210);
FORCEPROP 2 LASTPIN (-625 4150) $PN EA16
J 0
(-615 4160);
DISPLAY 0.617021 (-615 4160);
PAINT ORANGE (-615 4160);
FORCEPROP 2 LASTPIN (-625 4100) $PN EA20
J 0
(-615 4110);
DISPLAY 0.617021 (-615 4110);
PAINT ORANGE (-615 4110);
FORCEPROP 2 LASTPIN (-625 4050) $PN EA22
J 0
(-615 4060);
DISPLAY 0.617021 (-615 4060);
PAINT ORANGE (-615 4060);
FORCEPROP 2 LASTPIN (-625 4000) $PN EA42
J 0
(-615 4010);
DISPLAY 0.617021 (-615 4010);
PAINT ORANGE (-615 4010);
FORCEPROP 2 LASTPIN (-625 3950) $PN EA64
J 0
(-615 3960);
DISPLAY 0.617021 (-615 3960);
PAINT ORANGE (-615 3960);
FORCEPROP 2 LASTPIN (-625 3900) $PN EA70
J 0
(-615 3910);
DISPLAY 0.617021 (-615 3910);
PAINT ORANGE (-615 3910);
FORCEPROP 2 LASTPIN (-625 3850) $PN EA76
J 0
(-615 3860);
DISPLAY 0.617021 (-615 3860);
PAINT ORANGE (-615 3860);
FORCEPROP 2 LASTPIN (-625 3800) $PN EA78
J 0
(-615 3810);
DISPLAY 0.617021 (-615 3810);
PAINT ORANGE (-615 3810);
FORCEPROP 2 LASTPIN (-625 3750) $PN EA80
J 0
(-615 3760);
DISPLAY 0.617021 (-615 3760);
PAINT ORANGE (-615 3760);
FORCEPROP 2 LASTPIN (-625 3700) $PN EA82
J 0
(-615 3710);
DISPLAY 0.617021 (-615 3710);
PAINT ORANGE (-615 3710);
FORCEPROP 2 LASTPIN (-625 3650) $PN EB13
J 0
(-615 3660);
DISPLAY 0.617021 (-615 3660);
PAINT ORANGE (-615 3660);
FORCEPROP 2 LASTPIN (-625 3600) $PN BR18
J 0
(-615 3610);
DISPLAY 0.617021 (-615 3610);
PAINT ORANGE (-615 3610);
FORCEPROP 2 LASTPIN (-625 3550) $PN EB23
J 0
(-615 3560);
DISPLAY 0.617021 (-615 3560);
PAINT ORANGE (-615 3560);
FORCEPROP 2 LASTPIN (-625 3500) $PN EB25
J 0
(-615 3510);
DISPLAY 0.617021 (-615 3510);
PAINT ORANGE (-615 3510);
FORCEPROP 2 LASTPIN (-625 3450) $PN EB27
J 0
(-615 3460);
DISPLAY 0.617021 (-615 3460);
PAINT ORANGE (-615 3460);
FORCEPROP 2 LASTPIN (-625 3400) $PN EB29
J 0
(-615 3410);
DISPLAY 0.617021 (-615 3410);
PAINT ORANGE (-615 3410);
FORCEPROP 2 LASTPIN (-625 3350) $PN EB31
J 0
(-615 3360);
DISPLAY 0.617021 (-615 3360);
PAINT ORANGE (-615 3360);
FORCEPROP 2 LASTPIN (-625 3300) $PN EB33
J 0
(-615 3310);
DISPLAY 0.617021 (-615 3310);
PAINT ORANGE (-615 3310);
FORCEPROP 2 LASTPIN (-625 3250) $PN EB35
J 0
(-615 3260);
DISPLAY 0.617021 (-615 3260);
PAINT ORANGE (-615 3260);
FORCEPROP 2 LASTPIN (-625 3200) $PN EB37
J 0
(-615 3210);
DISPLAY 0.617021 (-615 3210);
PAINT ORANGE (-615 3210);
FORCEPROP 2 LASTPIN (-625 3150) $PN EB39
J 0
(-615 3160);
DISPLAY 0.617021 (-615 3160);
PAINT ORANGE (-615 3160);
FORCEPROP 2 LASTPIN (-625 3100) $PN EB41
J 0
(-615 3110);
DISPLAY 0.617021 (-615 3110);
PAINT ORANGE (-615 3110);
FORCEPROP 2 LASTPIN (-625 3050) $PN EB65
J 0
(-615 3060);
DISPLAY 0.617021 (-615 3060);
PAINT ORANGE (-615 3060);
FORCEPROP 2 LASTPIN (-625 3000) $PN EB69
J 0
(-615 3010);
DISPLAY 0.617021 (-615 3010);
PAINT ORANGE (-615 3010);
FORCEPROP 2 LASTPIN (-625 2950) $PN EC10
J 0
(-615 2960);
DISPLAY 0.617021 (-615 2960);
PAINT ORANGE (-615 2960);
FORCEPROP 2 LASTPIN (-625 2900) $PN EC70
J 0
(-615 2910);
DISPLAY 0.617021 (-615 2910);
PAINT ORANGE (-615 2910);
FORCEPROP 2 LASTPIN (-625 2850) $PN EC72
J 0
(-615 2860);
DISPLAY 0.617021 (-615 2860);
PAINT ORANGE (-615 2860);
FORCEPROP 2 LASTPIN (-625 2800) $PN EC74
J 0
(-615 2810);
DISPLAY 0.617021 (-615 2810);
PAINT ORANGE (-615 2810);
FORCEPROP 2 LASTPIN (-625 2750) $PN EC76
J 0
(-615 2760);
DISPLAY 0.617021 (-615 2760);
PAINT ORANGE (-615 2760);
FORCEPROP 2 LASTPIN (-625 2700) $PN ED11
J 0
(-615 2710);
DISPLAY 0.617021 (-615 2710);
PAINT ORANGE (-615 2710);
FORCEPROP 2 LASTPIN (-625 2650) $PN ED15
J 0
(-615 2660);
DISPLAY 0.617021 (-615 2660);
PAINT ORANGE (-615 2660);
FORCEPROP 2 LASTPIN (-625 2600) $PN ED23
J 0
(-615 2610);
DISPLAY 0.617021 (-615 2610);
PAINT ORANGE (-615 2610);
FORCEPROP 2 LASTPIN (-625 2550) $PN ED29
J 0
(-615 2560);
DISPLAY 0.617021 (-615 2560);
PAINT ORANGE (-615 2560);
FORCEPROP 2 LASTPIN (-625 2500) $PN ED35
J 0
(-615 2510);
DISPLAY 0.617021 (-615 2510);
PAINT ORANGE (-615 2510);
FORCEPROP 2 LASTPIN (-625 2450) $PN ED77
J 0
(-615 2460);
DISPLAY 0.617021 (-615 2460);
PAINT ORANGE (-615 2460);
FORCEPROP 2 LASTPIN (-625 2400) $PN EE24
J 0
(-615 2410);
DISPLAY 0.617021 (-615 2410);
PAINT ORANGE (-615 2410);
FORCEPROP 2 LASTPIN (-625 2350) $PN EE28
J 0
(-615 2360);
DISPLAY 0.617021 (-615 2360);
PAINT ORANGE (-615 2360);
FORCEPROP 2 LASTPIN (-625 2300) $PN EE30
J 0
(-615 2310);
DISPLAY 0.617021 (-615 2310);
PAINT ORANGE (-615 2310);
FORCEPROP 2 LASTPIN (-625 2250) $PN EE34
J 0
(-615 2260);
DISPLAY 0.617021 (-615 2260);
PAINT ORANGE (-615 2260);
FORCEPROP 2 LASTPIN (-625 2200) $PN EE36
J 0
(-615 2210);
DISPLAY 0.617021 (-615 2210);
PAINT ORANGE (-615 2210);
FORCEPROP 2 LASTPIN (-625 2150) $PN EE70
J 0
(-615 2160);
DISPLAY 0.617021 (-615 2160);
PAINT ORANGE (-615 2160);
FORCEPROP 2 LASTPIN (-625 2100) $PN EE76
J 0
(-615 2110);
DISPLAY 0.617021 (-615 2110);
PAINT ORANGE (-615 2110);
FORCEPROP 2 LASTPIN (-625 2050) $PN EE78
J 0
(-615 2060);
DISPLAY 0.617021 (-615 2060);
PAINT ORANGE (-615 2060);
FORCEPROP 2 LASTPIN (-625 2000) $PN EF71
J 0
(-615 2010);
DISPLAY 0.617021 (-615 2010);
PAINT ORANGE (-615 2010);
FORCEPROP 2 LASTPIN (-625 1950) $PN EF75
J 0
(-615 1960);
DISPLAY 0.617021 (-615 1960);
PAINT ORANGE (-615 1960);
FORCEPROP 2 LASTPIN (-625 1900) $PN EF79
J 0
(-615 1910);
DISPLAY 0.617021 (-615 1910);
PAINT ORANGE (-615 1910);
FORCEPROP 2 LASTPIN (-1825 2200) $PN DU80
J 2
(-1835 2210);
DISPLAY 0.617021 (-1835 2210);
PAINT ORANGE (-1835 2210);
FORCEPROP 2 LASTPIN (-1825 2550) $PN DU22
J 2
(-1835 2560);
DISPLAY 0.617021 (-1835 2560);
PAINT ORANGE (-1835 2560);
FORCEPROP 1 LAST PACK_TYPE BGA1
J 0
(-1775 4850);
PAINT SKYBLUE (-1775 4850);
DISPLAY INVISIBLE (-1775 4850);
FORCEPROP 2 LAST SEC_TYPE BGA1
J 0
(-1775 4850);
DISPLAY 1.021277 (-1775 4850);
PAINT ORANGE (-1775 4850);
DISPLAY INVISIBLE (-1775 4850);
FORCEPROP 2 LAST CDS_LIB chpset_lib
J 0
(-1225 2550);
PAINT ORANGE (-1225 2550);
DISPLAY INVISIBLE (-1225 2550);
FORCEPROP 2 LAST SEC 30
J 0
(-1775 4850);
DISPLAY 0.680851 (-1775 4850);
PAINT MONO (-1775 4850);
DISPLAY INVISIBLE (-1775 4850);
FORCEPROP 2 LAST CDS_LOCATION U2D1
J 0
(-1775 4800);
DISPLAY 0.617021 (-1775 4800);
PAINT AQUA (-1775 4800);
DISPLAY INVISIBLE (-1775 4800);
FORCEPROP 1 LAST PATH I20
J 0
(-1225 4750);
PAINT GREEN (-1225 4750);
DISPLAY INVISIBLE (-1225 4750);
FORCEADD GND..1
(-7475 400);
FORCEPROP 3 LASTPIN (-7475 450) SIG_NAME GND\g
J 0
(-7465 460);
DISPLAY 0.659574 (-7465 460);
PAINT MONO (-7465 460);
DISPLAY INVISIBLE (-7465 460);
FORCEPROP 1 LAST VOLTAGE 0.0V
J 0
(-7520 357);
DISPLAY 0.340426 (-7520 357);
PAINT SKYBLUE (-7520 357);
DISPLAY INVISIBLE (-7520 357);
FORCEPROP 2 LAST CDS_LIB mstr_symbols
J 0
(-7475 400);
PAINT ORANGE (-7475 400);
DISPLAY INVISIBLE (-7475 400);
FORCEPROP 1 LAST SIZE 1B
J 0
(-7400 350);
DISPLAY 1.170213 (-7400 350);
PAINT AQUA (-7400 350);
DISPLAY INVISIBLE (-7400 350);
FORCEPROP 1 LAST BODY_TYPE PLUMBING
J 0
(-7520 357);
DISPLAY 0.340426 (-7520 357);
PAINT GREEN (-7520 357);
DISPLAY INVISIBLE (-7520 357);
FORCEPROP 1 LAST PATH I9
J 0
(-7400 400);
DISPLAY 0.872340 (-7400 400);
PAINT AQUA (-7400 400);
DISPLAY INVISIBLE (-7400 400);
FORCEPROP 1 LAST HDL_POWER GND
J 0
(-7475 550);
DISPLAY 1.170213 (-7475 550);
PAINT GREEN (-7475 550);
DISPLAY INVISIBLE (-7475 550);
FORCEADD INTEL_CORP_BPAGE..1
(0 0);
FORCEPROP 1 LAST CDS_CON_LAST_MODIFIED Fri Jun 16 17:48:27 2017
J 0
(-1425 325);
DISPLAY 1.340426 (-1425 325);
PAINT GREEN (-1425 325);
DISPLAY INVISIBLE (-1425 325);
FORCEPROP 1 LAST CUSTOM_TXT_CDS <CURRENT_DESIGN_SHEET> OF <TOTAL_DESIGN_SHEETS>
J 0
(-500 25);
PAINT ORANGE (-500 25);
FORCEPROP 1 LAST CUSTOM_TXT_CDS <CON_LAST_MODIFIED>
J 0
(-4000 100);
PAINT ORANGE (-4000 100);
FORCEPROP 2 LAST CUSTOM_TXT_CDS <XR_PAGE_TITLE>
J 0
(-7890 5250);
DISPLAY 0.638298 (-7890 5250);
PAINT PINK (-7890 5250);
DISPLAY INVISIBLE (-7890 5250);
FORCEPROP 1 LAST SCH_TITLE SKYLAKE - SKT1 - 21 OF 21
J 0
(-7950 50);
DISPLAY 1.212766 (-7950 50);
PAINT GREEN (-7950 50);
FORCEPROP 2 LAST PAGE_BORDER TRUE
J 0
(-7890 5250);
DISPLAY 0.851064 (-7890 5250);
PAINT PINK (-7890 5250);
DISPLAY INVISIBLE (-7890 5250);
FORCEPROP 2 LAST CDS_LIB mstr_symbols
J 0
(0 0);
PAINT ORANGE (0 0);
DISPLAY INVISIBLE (0 0);
FORCEPROP 1 LAST COMMENT_BODY TRUE
J 0
(12 12);
DISPLAY 0.638298 (12 12);
PAINT GREEN (12 12);
DISPLAY INVISIBLE (12 12);
FORCEPROP 2 LAST CDS_XR_PAGE_TITLE CR-75 : @BASEBOARD_FAB2_LIB.BASEBOARD_FAB2(SCH_1):PAGE75
J 0
(-7890 5250);
DISPLAY 0.638298 (-7890 5250);
PAINT PINK (-7890 5250);
DISPLAY INVISIBLE (-7890 5250);
FORCEADD PRELIM..10
(-1215 2840);
PAINT GRAY (-1215 2840);
FORCEPROP 2 LAST CDS_LIB mstr_misc
J 0
(-1215 2840);
PAINT ORANGE (-1215 2840);
DISPLAY INVISIBLE (-1215 2840);
FORCEPROP 1 LAST COMMENT_BODY TRUE
J 0
(-1215 2840);
PAINT ORANGE (-1215 2840);
DISPLAY INVISIBLE (-1215 2840);
FORCEADD PRELIM..10
(-4890 2690);
PAINT GRAY (-4890 2690);
FORCEPROP 2 LAST CDS_LIB mstr_misc
J 0
(-4890 2690);
PAINT ORANGE (-4890 2690);
DISPLAY INVISIBLE (-4890 2690);
FORCEPROP 1 LAST COMMENT_BODY TRUE
J 0
(-4890 2690);
PAINT ORANGE (-4890 2690);
DISPLAY INVISIBLE (-4890 2690);
FORCEADD PRELIM..10
(-2965 2740);
PAINT GRAY (-2965 2740);
FORCEPROP 2 LAST CDS_LIB mstr_misc
J 0
(-2965 2740);
PAINT ORANGE (-2965 2740);
DISPLAY INVISIBLE (-2965 2740);
FORCEPROP 1 LAST COMMENT_BODY TRUE
J 0
(-2965 2740);
PAINT ORANGE (-2965 2740);
DISPLAY INVISIBLE (-2965 2740);
FORCEADD DESIGN_NOTE..1
(-6825 250);
FORCEPROP 0 LAST L1 CPU SYMBOLS 1-30 ARE PRELIMINARY AND SUBJECT TO CHANGE
J 0
(-7025 125);
DISPLAY 1.021277 (-7025 125);
PAINT ORANGE (-7025 125);
FORCEPROP 2 LAST CDS_LIB mstr_symbols
J 0
(-6825 250);
PAINT ORANGE (-6825 250);
DISPLAY INVISIBLE (-6825 250);
FORCEPROP 1 LAST COMMENT_BODY TRUE
J 0
(-6800 350);
DISPLAY 0.978723 (-6800 350);
PAINT ORANGE (-6800 350);
DISPLAY INVISIBLE (-6800 350);
FORCEADD PRELIM..10
(-6490 2490);
PAINT GRAY (-6490 2490);
FORCEPROP 2 LAST CDS_LIB mstr_misc
J 0
(-6490 2490);
PAINT ORANGE (-6490 2490);
DISPLAY INVISIBLE (-6490 2490);
FORCEPROP 1 LAST COMMENT_BODY TRUE
J 0
(-6490 2490);
PAINT ORANGE (-6490 2490);
DISPLAY INVISIBLE (-6490 2490);
WIRE 16 -1 (-5675 575)(-5675 450);
WIRE 16 -1 (-5675 625)(-5675 575);
WIRE 16 -1 (-5675 575)(-5525 575);
WIRE 16 -1 (-5675 675)(-5675 625);
WIRE 16 -1 (-5525 625)(-5675 625);
WIRE 16 -1 (-5675 725)(-5675 675);
WIRE 16 -1 (-5525 675)(-5675 675);
WIRE 16 -1 (-5675 775)(-5675 725);
WIRE 16 -1 (-5525 725)(-5675 725);
WIRE 16 -1 (-5675 825)(-5675 775);
WIRE 16 -1 (-5525 775)(-5675 775);
WIRE 16 -1 (-5675 875)(-5675 825);
WIRE 16 -1 (-5525 825)(-5675 825);
WIRE 16 -1 (-5675 925)(-5675 875);
WIRE 16 -1 (-5525 875)(-5675 875);
WIRE 16 -1 (-5675 975)(-5675 925);
WIRE 16 -1 (-5525 925)(-5675 925);
WIRE 16 -1 (-5675 1025)(-5675 975);
WIRE 16 -1 (-5525 975)(-5675 975);
WIRE 16 -1 (-5675 1075)(-5675 1025);
WIRE 16 -1 (-5525 1025)(-5675 1025);
WIRE 16 -1 (-5675 1125)(-5675 1075);
WIRE 16 -1 (-5525 1075)(-5675 1075);
WIRE 16 -1 (-5675 1175)(-5675 1125);
WIRE 16 -1 (-5525 1125)(-5675 1125);
WIRE 16 -1 (-5675 1225)(-5675 1175);
WIRE 16 -1 (-5525 1175)(-5675 1175);
WIRE 16 -1 (-5675 1275)(-5675 1225);
WIRE 16 -1 (-5525 1225)(-5675 1225);
WIRE 16 -1 (-5675 1325)(-5675 1275);
WIRE 16 -1 (-5525 1275)(-5675 1275);
WIRE 16 -1 (-5675 1375)(-5675 1325);
WIRE 16 -1 (-5525 1325)(-5675 1325);
WIRE 16 -1 (-5675 1425)(-5675 1375);
WIRE 16 -1 (-5525 1375)(-5675 1375);
WIRE 16 -1 (-5675 1475)(-5675 1425);
WIRE 16 -1 (-5525 1425)(-5675 1425);
WIRE 16 -1 (-5675 1525)(-5675 1475);
WIRE 16 -1 (-5525 1475)(-5675 1475);
WIRE 16 -1 (-5675 1575)(-5675 1525);
WIRE 16 -1 (-5525 1525)(-5675 1525);
WIRE 16 -1 (-5675 1625)(-5675 1575);
WIRE 16 -1 (-5525 1575)(-5675 1575);
WIRE 16 -1 (-5675 1675)(-5675 1625);
WIRE 16 -1 (-5525 1625)(-5675 1625);
WIRE 16 -1 (-5675 1725)(-5675 1675);
WIRE 16 -1 (-5525 1675)(-5675 1675);
WIRE 16 -1 (-5675 1775)(-5675 1725);
WIRE 16 -1 (-5525 1725)(-5675 1725);
WIRE 16 -1 (-5675 1825)(-5675 1775);
WIRE 16 -1 (-5525 1775)(-5675 1775);
WIRE 16 -1 (-5675 1875)(-5675 1825);
WIRE 16 -1 (-5525 1825)(-5675 1825);
WIRE 16 -1 (-5675 1925)(-5675 1875);
WIRE 16 -1 (-5525 1875)(-5675 1875);
WIRE 16 -1 (-5675 1975)(-5675 1925);
WIRE 16 -1 (-5525 1925)(-5675 1925);
WIRE 16 -1 (-5675 2025)(-5675 1975);
WIRE 16 -1 (-5525 1975)(-5675 1975);
WIRE 16 -1 (-5675 2075)(-5675 2025);
WIRE 16 -1 (-5525 2025)(-5675 2025);
WIRE 16 -1 (-5675 2125)(-5675 2075);
WIRE 16 -1 (-5525 2075)(-5675 2075);
WIRE 16 -1 (-5675 2175)(-5675 2125);
WIRE 16 -1 (-5525 2125)(-5675 2125);
WIRE 16 -1 (-5675 2225)(-5675 2175);
WIRE 16 -1 (-5525 2175)(-5675 2175);
WIRE 16 -1 (-5675 2275)(-5675 2225);
WIRE 16 -1 (-5525 2225)(-5675 2225);
WIRE 16 -1 (-5675 2325)(-5675 2275);
WIRE 16 -1 (-5525 2275)(-5675 2275);
WIRE 16 -1 (-5675 2375)(-5675 2325);
WIRE 16 -1 (-5525 2325)(-5675 2325);
WIRE 16 -1 (-5675 2425)(-5675 2375);
WIRE 16 -1 (-5525 2375)(-5675 2375);
WIRE 16 -1 (-5675 2475)(-5675 2425);
WIRE 16 -1 (-5525 2425)(-5675 2425);
WIRE 16 -1 (-5675 2525)(-5675 2475);
WIRE 16 -1 (-5525 2475)(-5675 2475);
WIRE 16 -1 (-5675 2575)(-5675 2525);
WIRE 16 -1 (-5525 2525)(-5675 2525);
WIRE 16 -1 (-5675 2625)(-5675 2575);
WIRE 16 -1 (-5525 2575)(-5675 2575);
WIRE 16 -1 (-5675 2675)(-5675 2625);
WIRE 16 -1 (-5525 2625)(-5675 2625);
WIRE 16 -1 (-5675 2725)(-5675 2675);
WIRE 16 -1 (-5525 2675)(-5675 2675);
WIRE 16 -1 (-5675 2775)(-5675 2725);
WIRE 16 -1 (-5525 2725)(-5675 2725);
WIRE 16 -1 (-5675 2825)(-5675 2775);
WIRE 16 -1 (-5525 2775)(-5675 2775);
WIRE 16 -1 (-5675 2875)(-5675 2825);
WIRE 16 -1 (-5525 2825)(-5675 2825);
WIRE 16 -1 (-5675 2925)(-5675 2875);
WIRE 16 -1 (-5525 2875)(-5675 2875);
WIRE 16 -1 (-5675 2975)(-5675 2925);
WIRE 16 -1 (-5525 2925)(-5675 2925);
WIRE 16 -1 (-5675 3025)(-5675 2975);
WIRE 16 -1 (-5525 2975)(-5675 2975);
WIRE 16 -1 (-5675 3075)(-5675 3025);
WIRE 16 -1 (-5525 3025)(-5675 3025);
WIRE 16 -1 (-5675 3125)(-5675 3075);
WIRE 16 -1 (-5525 3075)(-5675 3075);
WIRE 16 -1 (-5675 3175)(-5675 3125);
WIRE 16 -1 (-5525 3125)(-5675 3125);
WIRE 16 -1 (-5675 3225)(-5675 3175);
WIRE 16 -1 (-5525 3175)(-5675 3175);
WIRE 16 -1 (-5675 3275)(-5675 3225);
WIRE 16 -1 (-5525 3225)(-5675 3225);
WIRE 16 -1 (-5675 3325)(-5675 3275);
WIRE 16 -1 (-5525 3275)(-5675 3275);
WIRE 16 -1 (-5675 3375)(-5675 3325);
WIRE 16 -1 (-5525 3325)(-5675 3325);
WIRE 16 -1 (-5675 3425)(-5675 3375);
WIRE 16 -1 (-5525 3375)(-5675 3375);
WIRE 16 -1 (-5675 3475)(-5675 3425);
WIRE 16 -1 (-5525 3425)(-5675 3425);
WIRE 16 -1 (-5675 3525)(-5675 3475);
WIRE 16 -1 (-5525 3475)(-5675 3475);
WIRE 16 -1 (-5675 3575)(-5675 3525);
WIRE 16 -1 (-5525 3525)(-5675 3525);
WIRE 16 -1 (-5675 3625)(-5675 3575);
WIRE 16 -1 (-5525 3575)(-5675 3575);
WIRE 16 -1 (-5675 3675)(-5675 3625);
WIRE 16 -1 (-5525 3625)(-5675 3625);
WIRE 16 -1 (-5675 3725)(-5675 3675);
WIRE 16 -1 (-5525 3675)(-5675 3675);
WIRE 16 -1 (-5675 3775)(-5675 3725);
WIRE 16 -1 (-5525 3725)(-5675 3725);
WIRE 16 -1 (-5675 3825)(-5675 3775);
WIRE 16 -1 (-5525 3775)(-5675 3775);
WIRE 16 -1 (-5675 3875)(-5675 3825);
WIRE 16 -1 (-5525 3825)(-5675 3825);
WIRE 16 -1 (-5675 3925)(-5675 3875);
WIRE 16 -1 (-5525 3875)(-5675 3875);
WIRE 16 -1 (-5675 3975)(-5675 3925);
WIRE 16 -1 (-5525 3925)(-5675 3925);
WIRE 16 -1 (-5675 4025)(-5675 3975);
WIRE 16 -1 (-5525 3975)(-5675 3975);
WIRE 16 -1 (-5675 4075)(-5675 4025);
WIRE 16 -1 (-5525 4025)(-5675 4025);
WIRE 16 -1 (-5675 4125)(-5675 4075);
WIRE 16 -1 (-5525 4075)(-5675 4075);
WIRE 16 -1 (-5675 4175)(-5675 4125);
WIRE 16 -1 (-5525 4125)(-5675 4125);
WIRE 16 -1 (-5675 4225)(-5675 4175);
WIRE 16 -1 (-5525 4175)(-5675 4175);
WIRE 16 -1 (-5675 4275)(-5675 4225);
WIRE 16 -1 (-5525 4225)(-5675 4225);
WIRE 16 -1 (-5675 4325)(-5675 4275);
WIRE 16 -1 (-5525 4275)(-5675 4275);
WIRE 16 -1 (-5675 4375)(-5675 4325);
WIRE 16 -1 (-5525 4325)(-5675 4325);
WIRE 16 -1 (-5675 4425)(-5675 4375);
WIRE 16 -1 (-5525 4375)(-5675 4375);
WIRE 16 -1 (-5675 4475)(-5675 4425);
WIRE 16 -1 (-5525 4425)(-5675 4425);
WIRE 16 -1 (-5675 4525)(-5675 4475);
WIRE 16 -1 (-5525 4475)(-5675 4475);
WIRE 16 -1 (-5675 4525)(-5525 4525);
WIRE 16 -1 (-3775 575)(-3775 450);
WIRE 16 -1 (-3775 625)(-3775 575);
WIRE 16 -1 (-3775 575)(-3650 575);
WIRE 16 -1 (-3775 675)(-3775 625);
WIRE 16 -1 (-3650 625)(-3775 625);
WIRE 16 -1 (-3775 725)(-3775 675);
WIRE 16 -1 (-3650 675)(-3775 675);
WIRE 16 -1 (-3775 775)(-3775 725);
WIRE 16 -1 (-3650 725)(-3775 725);
WIRE 16 -1 (-3775 825)(-3775 775);
WIRE 16 -1 (-3650 775)(-3775 775);
WIRE 16 -1 (-3775 875)(-3775 825);
WIRE 16 -1 (-3650 825)(-3775 825);
WIRE 16 -1 (-3775 925)(-3775 875);
WIRE 16 -1 (-3650 875)(-3775 875);
WIRE 16 -1 (-3775 975)(-3775 925);
WIRE 16 -1 (-3650 925)(-3775 925);
WIRE 16 -1 (-3775 1025)(-3775 975);
WIRE 16 -1 (-3650 975)(-3775 975);
WIRE 16 -1 (-3775 1075)(-3775 1025);
WIRE 16 -1 (-3650 1025)(-3775 1025);
WIRE 16 -1 (-3775 1125)(-3775 1075);
WIRE 16 -1 (-3650 1075)(-3775 1075);
WIRE 16 -1 (-3775 1175)(-3775 1125);
WIRE 16 -1 (-3650 1125)(-3775 1125);
WIRE 16 -1 (-3775 1225)(-3775 1175);
WIRE 16 -1 (-3650 1175)(-3775 1175);
WIRE 16 -1 (-3775 1275)(-3775 1225);
WIRE 16 -1 (-3650 1225)(-3775 1225);
WIRE 16 -1 (-3775 1325)(-3775 1275);
WIRE 16 -1 (-3650 1275)(-3775 1275);
WIRE 16 -1 (-3775 1375)(-3775 1325);
WIRE 16 -1 (-3650 1325)(-3775 1325);
WIRE 16 -1 (-3775 1425)(-3775 1375);
WIRE 16 -1 (-3650 1375)(-3775 1375);
WIRE 16 -1 (-3775 1475)(-3775 1425);
WIRE 16 -1 (-3650 1425)(-3775 1425);
WIRE 16 -1 (-3775 1525)(-3775 1475);
WIRE 16 -1 (-3650 1475)(-3775 1475);
WIRE 16 -1 (-3775 1575)(-3775 1525);
WIRE 16 -1 (-3650 1525)(-3775 1525);
WIRE 16 -1 (-3775 1625)(-3775 1575);
WIRE 16 -1 (-3650 1575)(-3775 1575);
WIRE 16 -1 (-3775 1675)(-3775 1625);
WIRE 16 -1 (-3650 1625)(-3775 1625);
WIRE 16 -1 (-3775 1725)(-3775 1675);
WIRE 16 -1 (-3650 1675)(-3775 1675);
WIRE 16 -1 (-3775 1775)(-3775 1725);
WIRE 16 -1 (-3650 1725)(-3775 1725);
WIRE 16 -1 (-3775 1825)(-3775 1775);
WIRE 16 -1 (-3650 1775)(-3775 1775);
WIRE 16 -1 (-3775 1875)(-3775 1825);
WIRE 16 -1 (-3650 1825)(-3775 1825);
WIRE 16 -1 (-3775 1925)(-3775 1875);
WIRE 16 -1 (-3650 1875)(-3775 1875);
WIRE 16 -1 (-3775 1975)(-3775 1925);
WIRE 16 -1 (-3650 1925)(-3775 1925);
WIRE 16 -1 (-3775 2025)(-3775 1975);
WIRE 16 -1 (-3650 1975)(-3775 1975);
WIRE 16 -1 (-3775 2075)(-3775 2025);
WIRE 16 -1 (-3650 2025)(-3775 2025);
WIRE 16 -1 (-3775 2125)(-3775 2075);
WIRE 16 -1 (-3650 2075)(-3775 2075);
WIRE 16 -1 (-3775 2175)(-3775 2125);
WIRE 16 -1 (-3650 2125)(-3775 2125);
WIRE 16 -1 (-3775 2225)(-3775 2175);
WIRE 16 -1 (-3650 2175)(-3775 2175);
WIRE 16 -1 (-3775 2275)(-3775 2225);
WIRE 16 -1 (-3650 2225)(-3775 2225);
WIRE 16 -1 (-3775 2325)(-3775 2275);
WIRE 16 -1 (-3650 2275)(-3775 2275);
WIRE 16 -1 (-3775 2375)(-3775 2325);
WIRE 16 -1 (-3650 2325)(-3775 2325);
WIRE 16 -1 (-3775 2425)(-3775 2375);
WIRE 16 -1 (-3650 2375)(-3775 2375);
WIRE 16 -1 (-3775 2475)(-3775 2425);
WIRE 16 -1 (-3650 2425)(-3775 2425);
WIRE 16 -1 (-3775 2525)(-3775 2475);
WIRE 16 -1 (-3650 2475)(-3775 2475);
WIRE 16 -1 (-3775 2575)(-3775 2525);
WIRE 16 -1 (-3650 2525)(-3775 2525);
WIRE 16 -1 (-3775 2625)(-3775 2575);
WIRE 16 -1 (-3650 2575)(-3775 2575);
WIRE 16 -1 (-3775 2675)(-3775 2625);
WIRE 16 -1 (-3650 2625)(-3775 2625);
WIRE 16 -1 (-3775 2725)(-3775 2675);
WIRE 16 -1 (-3650 2675)(-3775 2675);
WIRE 16 -1 (-3775 2775)(-3775 2725);
WIRE 16 -1 (-3650 2725)(-3775 2725);
WIRE 16 -1 (-3775 2825)(-3775 2775);
WIRE 16 -1 (-3650 2775)(-3775 2775);
WIRE 16 -1 (-3775 2875)(-3775 2825);
WIRE 16 -1 (-3650 2825)(-3775 2825);
WIRE 16 -1 (-3775 2925)(-3775 2875);
WIRE 16 -1 (-3650 2875)(-3775 2875);
WIRE 16 -1 (-3775 2975)(-3775 2925);
WIRE 16 -1 (-3650 2925)(-3775 2925);
WIRE 16 -1 (-3775 3025)(-3775 2975);
WIRE 16 -1 (-3650 2975)(-3775 2975);
WIRE 16 -1 (-3775 3075)(-3775 3025);
WIRE 16 -1 (-3650 3025)(-3775 3025);
WIRE 16 -1 (-3775 3125)(-3775 3075);
WIRE 16 -1 (-3650 3075)(-3775 3075);
WIRE 16 -1 (-3775 3175)(-3775 3125);
WIRE 16 -1 (-3650 3125)(-3775 3125);
WIRE 16 -1 (-3775 3225)(-3775 3175);
WIRE 16 -1 (-3650 3175)(-3775 3175);
WIRE 16 -1 (-3775 3275)(-3775 3225);
WIRE 16 -1 (-3650 3225)(-3775 3225);
WIRE 16 -1 (-3775 3325)(-3775 3275);
WIRE 16 -1 (-3650 3275)(-3775 3275);
WIRE 16 -1 (-3775 3375)(-3775 3325);
WIRE 16 -1 (-3650 3325)(-3775 3325);
WIRE 16 -1 (-3775 3425)(-3775 3375);
WIRE 16 -1 (-3650 3375)(-3775 3375);
WIRE 16 -1 (-3775 3475)(-3775 3425);
WIRE 16 -1 (-3650 3425)(-3775 3425);
WIRE 16 -1 (-3775 3525)(-3775 3475);
WIRE 16 -1 (-3650 3475)(-3775 3475);
WIRE 16 -1 (-3775 3575)(-3775 3525);
WIRE 16 -1 (-3650 3525)(-3775 3525);
WIRE 16 -1 (-3775 3625)(-3775 3575);
WIRE 16 -1 (-3650 3575)(-3775 3575);
WIRE 16 -1 (-3775 3675)(-3775 3625);
WIRE 16 -1 (-3650 3625)(-3775 3625);
WIRE 16 -1 (-3775 3725)(-3775 3675);
WIRE 16 -1 (-3650 3675)(-3775 3675);
WIRE 16 -1 (-3775 3775)(-3775 3725);
WIRE 16 -1 (-3650 3725)(-3775 3725);
WIRE 16 -1 (-3775 3825)(-3775 3775);
WIRE 16 -1 (-3650 3775)(-3775 3775);
WIRE 16 -1 (-3775 3875)(-3775 3825);
WIRE 16 -1 (-3650 3825)(-3775 3825);
WIRE 16 -1 (-3775 3925)(-3775 3875);
WIRE 16 -1 (-3650 3875)(-3775 3875);
WIRE 16 -1 (-3775 3975)(-3775 3925);
WIRE 16 -1 (-3650 3925)(-3775 3925);
WIRE 16 -1 (-3775 4025)(-3775 3975);
WIRE 16 -1 (-3650 3975)(-3775 3975);
WIRE 16 -1 (-3775 4075)(-3775 4025);
WIRE 16 -1 (-3650 4025)(-3775 4025);
WIRE 16 -1 (-3775 4125)(-3775 4075);
WIRE 16 -1 (-3650 4075)(-3775 4075);
WIRE 16 -1 (-3775 4175)(-3775 4125);
WIRE 16 -1 (-3650 4125)(-3775 4125);
WIRE 16 -1 (-3775 4225)(-3775 4175);
WIRE 16 -1 (-3650 4175)(-3775 4175);
WIRE 16 -1 (-3775 4275)(-3775 4225);
WIRE 16 -1 (-3650 4225)(-3775 4225);
WIRE 16 -1 (-3775 4325)(-3775 4275);
WIRE 16 -1 (-3650 4275)(-3775 4275);
WIRE 16 -1 (-3775 4375)(-3775 4325);
WIRE 16 -1 (-3650 4325)(-3775 4325);
WIRE 16 -1 (-3775 4425)(-3775 4375);
WIRE 16 -1 (-3650 4375)(-3775 4375);
WIRE 16 -1 (-3775 4475)(-3775 4425);
WIRE 16 -1 (-3650 4425)(-3775 4425);
WIRE 16 -1 (-3775 4525)(-3775 4475);
WIRE 16 -1 (-3650 4475)(-3775 4475);
WIRE 16 -1 (-3775 4525)(-3650 4525);
WIRE 16 -1 (-1975 600)(-1975 450);
WIRE 16 -1 (-1975 650)(-1975 600);
WIRE 16 -1 (-1825 600)(-1975 600);
WIRE 16 -1 (-1975 700)(-1975 650);
WIRE 16 -1 (-1825 650)(-1975 650);
WIRE 16 -1 (-1975 750)(-1975 700);
WIRE 16 -1 (-1825 700)(-1975 700);
WIRE 16 -1 (-1975 800)(-1975 750);
WIRE 16 -1 (-1825 750)(-1975 750);
WIRE 16 -1 (-1975 850)(-1975 800);
WIRE 16 -1 (-1825 800)(-1975 800);
WIRE 16 -1 (-1975 900)(-1975 850);
WIRE 16 -1 (-1825 850)(-1975 850);
WIRE 16 -1 (-1975 950)(-1975 900);
WIRE 16 -1 (-1825 900)(-1975 900);
WIRE 16 -1 (-1975 1000)(-1975 950);
WIRE 16 -1 (-1825 950)(-1975 950);
WIRE 16 -1 (-1975 1050)(-1975 1000);
WIRE 16 -1 (-1825 1000)(-1975 1000);
WIRE 16 -1 (-1975 1100)(-1975 1050);
WIRE 16 -1 (-1825 1050)(-1975 1050);
WIRE 16 -1 (-1975 1150)(-1975 1100);
WIRE 16 -1 (-1825 1100)(-1975 1100);
WIRE 16 -1 (-1975 1200)(-1975 1150);
WIRE 16 -1 (-1825 1150)(-1975 1150);
WIRE 16 -1 (-1975 1250)(-1975 1200);
WIRE 16 -1 (-1825 1200)(-1975 1200);
WIRE 16 -1 (-1975 1300)(-1975 1250);
WIRE 16 -1 (-1825 1250)(-1975 1250);
WIRE 16 -1 (-1975 1300)(-1975 1350);
WIRE 16 -1 (-1825 1300)(-1975 1300);
WIRE 16 -1 (-1975 1350)(-1975 1400);
WIRE 16 -1 (-1825 1350)(-1975 1350);
WIRE 16 -1 (-1975 1400)(-1975 1450);
WIRE 16 -1 (-1825 1400)(-1975 1400);
WIRE 16 -1 (-1975 1450)(-1975 1500);
WIRE 16 -1 (-1825 1450)(-1975 1450);
WIRE 16 -1 (-1975 1500)(-1975 1550);
WIRE 16 -1 (-1825 1500)(-1975 1500);
WIRE 16 -1 (-1975 1550)(-1975 1600);
WIRE 16 -1 (-1825 1550)(-1975 1550);
WIRE 16 -1 (-1975 1600)(-1975 1650);
WIRE 16 -1 (-1825 1600)(-1975 1600);
WIRE 16 -1 (-1975 1650)(-1975 1700);
WIRE 16 -1 (-1825 1650)(-1975 1650);
WIRE 16 -1 (-1975 1700)(-1975 1750);
WIRE 16 -1 (-1825 1700)(-1975 1700);
WIRE 16 -1 (-1975 1750)(-1975 1800);
WIRE 16 -1 (-1825 1750)(-1975 1750);
WIRE 16 -1 (-1975 1800)(-1975 1850);
WIRE 16 -1 (-1825 1800)(-1975 1800);
WIRE 16 -1 (-1975 1850)(-1975 1900);
WIRE 16 -1 (-1825 1850)(-1975 1850);
WIRE 16 -1 (-1975 1900)(-1975 1950);
WIRE 16 -1 (-1825 1900)(-1975 1900);
WIRE 16 -1 (-1975 1950)(-1975 2000);
WIRE 16 -1 (-1825 1950)(-1975 1950);
WIRE 16 -1 (-1975 2000)(-1975 2050);
WIRE 16 -1 (-1825 2000)(-1975 2000);
WIRE 16 -1 (-1975 2050)(-1975 2100);
WIRE 16 -1 (-1825 2050)(-1975 2050);
WIRE 16 -1 (-1975 2100)(-1975 2150);
WIRE 16 -1 (-1825 2100)(-1975 2100);
WIRE 16 -1 (-1975 2150)(-1975 2200);
WIRE 16 -1 (-1825 2150)(-1975 2150);
WIRE 16 -1 (-1975 2200)(-1975 2250);
WIRE 16 -1 (-1825 2200)(-1975 2200);
WIRE 16 -1 (-1975 2250)(-1975 2300);
WIRE 16 -1 (-1825 2250)(-1975 2250);
WIRE 16 -1 (-1975 2300)(-1975 2350);
WIRE 16 -1 (-1825 2300)(-1975 2300);
WIRE 16 -1 (-1975 2350)(-1975 2400);
WIRE 16 -1 (-1825 2350)(-1975 2350);
WIRE 16 -1 (-1975 2400)(-1975 2450);
WIRE 16 -1 (-1825 2400)(-1975 2400);
WIRE 16 -1 (-1975 2450)(-1975 2500);
WIRE 16 -1 (-1825 2450)(-1975 2450);
WIRE 16 -1 (-1975 2500)(-1975 2550);
WIRE 16 -1 (-1825 2500)(-1975 2500);
WIRE 16 -1 (-1975 2550)(-1975 2600);
WIRE 16 -1 (-1825 2550)(-1975 2550);
WIRE 16 -1 (-1975 2600)(-1975 2650);
WIRE 16 -1 (-1825 2600)(-1975 2600);
WIRE 16 -1 (-1975 2650)(-1975 2700);
WIRE 16 -1 (-1825 2650)(-1975 2650);
WIRE 16 -1 (-1975 2700)(-1975 2750);
WIRE 16 -1 (-1825 2700)(-1975 2700);
WIRE 16 -1 (-1975 2750)(-1975 2800);
WIRE 16 -1 (-1825 2750)(-1975 2750);
WIRE 16 -1 (-1975 2800)(-1975 2850);
WIRE 16 -1 (-1825 2800)(-1975 2800);
WIRE 16 -1 (-1975 2850)(-1975 2900);
WIRE 16 -1 (-1825 2850)(-1975 2850);
WIRE 16 -1 (-1975 2900)(-1975 2950);
WIRE 16 -1 (-1825 2900)(-1975 2900);
WIRE 16 -1 (-1975 2950)(-1975 3000);
WIRE 16 -1 (-1825 2950)(-1975 2950);
WIRE 16 -1 (-1975 3000)(-1975 3050);
WIRE 16 -1 (-1825 3000)(-1975 3000);
WIRE 16 -1 (-1975 3050)(-1975 3100);
WIRE 16 -1 (-1825 3050)(-1975 3050);
WIRE 16 -1 (-1975 3100)(-1975 3150);
WIRE 16 -1 (-1825 3100)(-1975 3100);
WIRE 16 -1 (-1975 3150)(-1975 3200);
WIRE 16 -1 (-1825 3150)(-1975 3150);
WIRE 16 -1 (-1975 3200)(-1975 3250);
WIRE 16 -1 (-1825 3200)(-1975 3200);
WIRE 16 -1 (-1975 3250)(-1975 3300);
WIRE 16 -1 (-1825 3250)(-1975 3250);
WIRE 16 -1 (-1975 3300)(-1975 3350);
WIRE 16 -1 (-1825 3300)(-1975 3300);
WIRE 16 -1 (-1975 3350)(-1975 3400);
WIRE 16 -1 (-1825 3350)(-1975 3350);
WIRE 16 -1 (-1975 3400)(-1975 3450);
WIRE 16 -1 (-1825 3400)(-1975 3400);
WIRE 16 -1 (-1975 3450)(-1975 3500);
WIRE 16 -1 (-1825 3450)(-1975 3450);
WIRE 16 -1 (-1975 3500)(-1975 3550);
WIRE 16 -1 (-1825 3500)(-1975 3500);
WIRE 16 -1 (-1975 3550)(-1975 3600);
WIRE 16 -1 (-1825 3550)(-1975 3550);
WIRE 16 -1 (-1975 3600)(-1975 3650);
WIRE 16 -1 (-1825 3600)(-1975 3600);
WIRE 16 -1 (-1975 3650)(-1975 3700);
WIRE 16 -1 (-1825 3650)(-1975 3650);
WIRE 16 -1 (-1975 3700)(-1975 3750);
WIRE 16 -1 (-1825 3700)(-1975 3700);
WIRE 16 -1 (-1975 3750)(-1975 3800);
WIRE 16 -1 (-1825 3750)(-1975 3750);
WIRE 16 -1 (-1975 3800)(-1975 3850);
WIRE 16 -1 (-1825 3800)(-1975 3800);
WIRE 16 -1 (-1975 3850)(-1975 3900);
WIRE 16 -1 (-1825 3850)(-1975 3850);
WIRE 16 -1 (-1975 3900)(-1975 3950);
WIRE 16 -1 (-1825 3900)(-1975 3900);
WIRE 16 -1 (-1975 3950)(-1975 4000);
WIRE 16 -1 (-1825 3950)(-1975 3950);
WIRE 16 -1 (-1975 4000)(-1975 4050);
WIRE 16 -1 (-1825 4000)(-1975 4000);
WIRE 16 -1 (-1975 4050)(-1975 4100);
WIRE 16 -1 (-1825 4050)(-1975 4050);
WIRE 16 -1 (-1975 4100)(-1975 4150);
WIRE 16 -1 (-1825 4100)(-1975 4100);
WIRE 16 -1 (-1975 4150)(-1975 4200);
WIRE 16 -1 (-1825 4150)(-1975 4150);
WIRE 16 -1 (-1975 4250)(-1975 4200);
WIRE 16 -1 (-1825 4200)(-1975 4200);
WIRE 16 -1 (-1975 4300)(-1975 4250);
WIRE 16 -1 (-1825 4250)(-1975 4250);
WIRE 16 -1 (-1975 4350)(-1975 4300);
WIRE 16 -1 (-1825 4300)(-1975 4300);
WIRE 16 -1 (-1975 4400)(-1975 4350);
WIRE 16 -1 (-1825 4350)(-1975 4350);
WIRE 16 -1 (-1975 4450)(-1975 4400);
WIRE 16 -1 (-1825 4400)(-1975 4400);
WIRE 16 -1 (-1975 4500)(-1975 4450);
WIRE 16 -1 (-1825 4450)(-1975 4450);
WIRE 16 -1 (-1975 4550)(-1975 4500);
WIRE 16 -1 (-1825 4500)(-1975 4500);
WIRE 16 -1 (-1975 4550)(-1825 4550);
WIRE 16 -1 (-2275 575)(-2275 450);
WIRE 16 -1 (-2275 625)(-2275 575);
WIRE 16 -1 (-2450 575)(-2275 575);
WIRE 16 -1 (-2275 675)(-2275 625);
WIRE 16 -1 (-2450 625)(-2275 625);
WIRE 16 -1 (-2275 725)(-2275 675);
WIRE 16 -1 (-2450 675)(-2275 675);
WIRE 16 -1 (-2275 775)(-2275 725);
WIRE 16 -1 (-2450 725)(-2275 725);
WIRE 16 -1 (-2275 825)(-2275 775);
WIRE 16 -1 (-2450 775)(-2275 775);
WIRE 16 -1 (-2275 875)(-2275 825);
WIRE 16 -1 (-2450 825)(-2275 825);
WIRE 16 -1 (-2275 925)(-2275 875);
WIRE 16 -1 (-2450 875)(-2275 875);
WIRE 16 -1 (-2275 975)(-2275 925);
WIRE 16 -1 (-2450 925)(-2275 925);
WIRE 16 -1 (-2275 1025)(-2275 975);
WIRE 16 -1 (-2450 975)(-2275 975);
WIRE 16 -1 (-2275 1075)(-2275 1025);
WIRE 16 -1 (-2450 1025)(-2275 1025);
WIRE 16 -1 (-2275 1125)(-2275 1075);
WIRE 16 -1 (-2450 1075)(-2275 1075);
WIRE 16 -1 (-2275 1175)(-2275 1125);
WIRE 16 -1 (-2450 1125)(-2275 1125);
WIRE 16 -1 (-2275 1225)(-2275 1175);
WIRE 16 -1 (-2450 1175)(-2275 1175);
WIRE 16 -1 (-2275 1275)(-2275 1225);
WIRE 16 -1 (-2450 1225)(-2275 1225);
WIRE 16 -1 (-2275 1325)(-2275 1275);
WIRE 16 -1 (-2450 1275)(-2275 1275);
WIRE 16 -1 (-2275 1375)(-2275 1325);
WIRE 16 -1 (-2450 1325)(-2275 1325);
WIRE 16 -1 (-2275 1425)(-2275 1375);
WIRE 16 -1 (-2450 1375)(-2275 1375);
WIRE 16 -1 (-2275 1475)(-2275 1425);
WIRE 16 -1 (-2450 1425)(-2275 1425);
WIRE 16 -1 (-2275 1525)(-2275 1475);
WIRE 16 -1 (-2450 1475)(-2275 1475);
WIRE 16 -1 (-2275 1575)(-2275 1525);
WIRE 16 -1 (-2450 1525)(-2275 1525);
WIRE 16 -1 (-2275 1625)(-2275 1575);
WIRE 16 -1 (-2450 1575)(-2275 1575);
WIRE 16 -1 (-2275 1675)(-2275 1625);
WIRE 16 -1 (-2450 1625)(-2275 1625);
WIRE 16 -1 (-2275 1725)(-2275 1675);
WIRE 16 -1 (-2450 1675)(-2275 1675);
WIRE 16 -1 (-2275 1775)(-2275 1725);
WIRE 16 -1 (-2450 1725)(-2275 1725);
WIRE 16 -1 (-2275 1825)(-2275 1775);
WIRE 16 -1 (-2450 1775)(-2275 1775);
WIRE 16 -1 (-2275 1875)(-2275 1825);
WIRE 16 -1 (-2450 1825)(-2275 1825);
WIRE 16 -1 (-2275 1925)(-2275 1875);
WIRE 16 -1 (-2450 1875)(-2275 1875);
WIRE 16 -1 (-2275 1975)(-2275 1925);
WIRE 16 -1 (-2450 1925)(-2275 1925);
WIRE 16 -1 (-2275 2025)(-2275 1975);
WIRE 16 -1 (-2450 1975)(-2275 1975);
WIRE 16 -1 (-2275 2075)(-2275 2025);
WIRE 16 -1 (-2450 2025)(-2275 2025);
WIRE 16 -1 (-2275 2125)(-2275 2075);
WIRE 16 -1 (-2450 2075)(-2275 2075);
WIRE 16 -1 (-2275 2175)(-2275 2125);
WIRE 16 -1 (-2450 2125)(-2275 2125);
WIRE 16 -1 (-2275 2225)(-2275 2175);
WIRE 16 -1 (-2450 2175)(-2275 2175);
WIRE 16 -1 (-2275 2275)(-2275 2225);
WIRE 16 -1 (-2450 2225)(-2275 2225);
WIRE 16 -1 (-2275 2325)(-2275 2275);
WIRE 16 -1 (-2450 2275)(-2275 2275);
WIRE 16 -1 (-2275 2375)(-2275 2325);
WIRE 16 -1 (-2450 2325)(-2275 2325);
WIRE 16 -1 (-2275 2425)(-2275 2375);
WIRE 16 -1 (-2450 2375)(-2275 2375);
WIRE 16 -1 (-2275 2475)(-2275 2425);
WIRE 16 -1 (-2450 2425)(-2275 2425);
WIRE 16 -1 (-2275 2525)(-2275 2475);
WIRE 16 -1 (-2450 2475)(-2275 2475);
WIRE 16 -1 (-2275 2575)(-2275 2525);
WIRE 16 -1 (-2450 2525)(-2275 2525);
WIRE 16 -1 (-2275 2625)(-2275 2575);
WIRE 16 -1 (-2450 2575)(-2275 2575);
WIRE 16 -1 (-2275 2675)(-2275 2625);
WIRE 16 -1 (-2450 2625)(-2275 2625);
WIRE 16 -1 (-2275 2725)(-2275 2675);
WIRE 16 -1 (-2450 2675)(-2275 2675);
WIRE 16 -1 (-2275 2775)(-2275 2725);
WIRE 16 -1 (-2450 2725)(-2275 2725);
WIRE 16 -1 (-2275 2825)(-2275 2775);
WIRE 16 -1 (-2450 2775)(-2275 2775);
WIRE 16 -1 (-2275 2875)(-2275 2825);
WIRE 16 -1 (-2450 2825)(-2275 2825);
WIRE 16 -1 (-2275 2925)(-2275 2875);
WIRE 16 -1 (-2450 2875)(-2275 2875);
WIRE 16 -1 (-2275 2975)(-2275 2925);
WIRE 16 -1 (-2450 2925)(-2275 2925);
WIRE 16 -1 (-2275 3025)(-2275 2975);
WIRE 16 -1 (-2450 2975)(-2275 2975);
WIRE 16 -1 (-2275 3075)(-2275 3025);
WIRE 16 -1 (-2450 3025)(-2275 3025);
WIRE 16 -1 (-2275 3125)(-2275 3075);
WIRE 16 -1 (-2450 3075)(-2275 3075);
WIRE 16 -1 (-2275 3175)(-2275 3125);
WIRE 16 -1 (-2450 3125)(-2275 3125);
WIRE 16 -1 (-2275 3225)(-2275 3175);
WIRE 16 -1 (-2450 3175)(-2275 3175);
WIRE 16 -1 (-2275 3275)(-2275 3225);
WIRE 16 -1 (-2450 3225)(-2275 3225);
WIRE 16 -1 (-2275 3325)(-2275 3275);
WIRE 16 -1 (-2450 3275)(-2275 3275);
WIRE 16 -1 (-2275 3375)(-2275 3325);
WIRE 16 -1 (-2450 3325)(-2275 3325);
WIRE 16 -1 (-2275 3425)(-2275 3375);
WIRE 16 -1 (-2450 3375)(-2275 3375);
WIRE 16 -1 (-2275 3475)(-2275 3425);
WIRE 16 -1 (-2450 3425)(-2275 3425);
WIRE 16 -1 (-2275 3525)(-2275 3475);
WIRE 16 -1 (-2450 3475)(-2275 3475);
WIRE 16 -1 (-2275 3575)(-2275 3525);
WIRE 16 -1 (-2450 3525)(-2275 3525);
WIRE 16 -1 (-2275 3625)(-2275 3575);
WIRE 16 -1 (-2450 3575)(-2275 3575);
WIRE 16 -1 (-2275 3675)(-2275 3625);
WIRE 16 -1 (-2450 3625)(-2275 3625);
WIRE 16 -1 (-2275 3725)(-2275 3675);
WIRE 16 -1 (-2450 3675)(-2275 3675);
WIRE 16 -1 (-2275 3775)(-2275 3725);
WIRE 16 -1 (-2450 3725)(-2275 3725);
WIRE 16 -1 (-2275 3825)(-2275 3775);
WIRE 16 -1 (-2450 3775)(-2275 3775);
WIRE 16 -1 (-2275 3875)(-2275 3825);
WIRE 16 -1 (-2450 3825)(-2275 3825);
WIRE 16 -1 (-2275 3925)(-2275 3875);
WIRE 16 -1 (-2450 3875)(-2275 3875);
WIRE 16 -1 (-2275 3975)(-2275 3925);
WIRE 16 -1 (-2450 3925)(-2275 3925);
WIRE 16 -1 (-2275 4025)(-2275 3975);
WIRE 16 -1 (-2450 3975)(-2275 3975);
WIRE 16 -1 (-2275 4075)(-2275 4025);
WIRE 16 -1 (-2450 4025)(-2275 4025);
WIRE 16 -1 (-2275 4125)(-2275 4075);
WIRE 16 -1 (-2450 4075)(-2275 4075);
WIRE 16 -1 (-2275 4175)(-2275 4125);
WIRE 16 -1 (-2450 4125)(-2275 4125);
WIRE 16 -1 (-2275 4225)(-2275 4175);
WIRE 16 -1 (-2450 4175)(-2275 4175);
WIRE 16 -1 (-2275 4275)(-2275 4225);
WIRE 16 -1 (-2450 4225)(-2275 4225);
WIRE 16 -1 (-2275 4325)(-2275 4275);
WIRE 16 -1 (-2450 4275)(-2275 4275);
WIRE 16 -1 (-2275 4375)(-2275 4325);
WIRE 16 -1 (-2450 4325)(-2275 4325);
WIRE 16 -1 (-2275 4425)(-2275 4375);
WIRE 16 -1 (-2450 4375)(-2275 4375);
WIRE 16 -1 (-2275 4475)(-2275 4425);
WIRE 16 -1 (-2450 4425)(-2275 4425);
WIRE 16 -1 (-2275 4525)(-2275 4475);
WIRE 16 -1 (-2450 4475)(-2275 4475);
WIRE 16 -1 (-2450 4525)(-2275 4525);
WIRE 16 -1 (-4150 575)(-4150 450);
WIRE 16 -1 (-4150 625)(-4150 575);
WIRE 16 -1 (-4325 575)(-4150 575);
WIRE 16 -1 (-4150 675)(-4150 625);
WIRE 16 -1 (-4325 625)(-4150 625);
WIRE 16 -1 (-4150 725)(-4150 675);
WIRE 16 -1 (-4325 675)(-4150 675);
WIRE 16 -1 (-4150 775)(-4150 725);
WIRE 16 -1 (-4325 725)(-4150 725);
WIRE 16 -1 (-4150 825)(-4150 775);
WIRE 16 -1 (-4325 775)(-4150 775);
WIRE 16 -1 (-4150 875)(-4150 825);
WIRE 16 -1 (-4325 825)(-4150 825);
WIRE 16 -1 (-4150 925)(-4150 875);
WIRE 16 -1 (-4325 875)(-4150 875);
WIRE 16 -1 (-4150 975)(-4150 925);
WIRE 16 -1 (-4325 925)(-4150 925);
WIRE 16 -1 (-4150 1025)(-4150 975);
WIRE 16 -1 (-4325 975)(-4150 975);
WIRE 16 -1 (-4150 1075)(-4150 1025);
WIRE 16 -1 (-4325 1025)(-4150 1025);
WIRE 16 -1 (-4150 1125)(-4150 1075);
WIRE 16 -1 (-4325 1075)(-4150 1075);
WIRE 16 -1 (-4150 1175)(-4150 1125);
WIRE 16 -1 (-4325 1125)(-4150 1125);
WIRE 16 -1 (-4150 1225)(-4150 1175);
WIRE 16 -1 (-4325 1175)(-4150 1175);
WIRE 16 -1 (-4150 1275)(-4150 1225);
WIRE 16 -1 (-4325 1225)(-4150 1225);
WIRE 16 -1 (-4150 1325)(-4150 1275);
WIRE 16 -1 (-4325 1275)(-4150 1275);
WIRE 16 -1 (-4150 1375)(-4150 1325);
WIRE 16 -1 (-4325 1325)(-4150 1325);
WIRE 16 -1 (-4150 1425)(-4150 1375);
WIRE 16 -1 (-4325 1375)(-4150 1375);
WIRE 16 -1 (-4150 1475)(-4150 1425);
WIRE 16 -1 (-4325 1425)(-4150 1425);
WIRE 16 -1 (-4150 1525)(-4150 1475);
WIRE 16 -1 (-4325 1475)(-4150 1475);
WIRE 16 -1 (-4150 1575)(-4150 1525);
WIRE 16 -1 (-4325 1525)(-4150 1525);
WIRE 16 -1 (-4150 1625)(-4150 1575);
WIRE 16 -1 (-4325 1575)(-4150 1575);
WIRE 16 -1 (-4150 1675)(-4150 1625);
WIRE 16 -1 (-4325 1625)(-4150 1625);
WIRE 16 -1 (-4150 1725)(-4150 1675);
WIRE 16 -1 (-4325 1675)(-4150 1675);
WIRE 16 -1 (-4150 1775)(-4150 1725);
WIRE 16 -1 (-4325 1725)(-4150 1725);
WIRE 16 -1 (-4150 1825)(-4150 1775);
WIRE 16 -1 (-4325 1775)(-4150 1775);
WIRE 16 -1 (-4150 1875)(-4150 1825);
WIRE 16 -1 (-4325 1825)(-4150 1825);
WIRE 16 -1 (-4150 1925)(-4150 1875);
WIRE 16 -1 (-4325 1875)(-4150 1875);
WIRE 16 -1 (-4150 1975)(-4150 1925);
WIRE 16 -1 (-4325 1925)(-4150 1925);
WIRE 16 -1 (-4150 2025)(-4150 1975);
WIRE 16 -1 (-4325 1975)(-4150 1975);
WIRE 16 -1 (-4150 2075)(-4150 2025);
WIRE 16 -1 (-4325 2025)(-4150 2025);
WIRE 16 -1 (-4150 2125)(-4150 2075);
WIRE 16 -1 (-4325 2075)(-4150 2075);
WIRE 16 -1 (-4150 2175)(-4150 2125);
WIRE 16 -1 (-4325 2125)(-4150 2125);
WIRE 16 -1 (-4150 2225)(-4150 2175);
WIRE 16 -1 (-4325 2175)(-4150 2175);
WIRE 16 -1 (-4150 2275)(-4150 2225);
WIRE 16 -1 (-4325 2225)(-4150 2225);
WIRE 16 -1 (-4150 2325)(-4150 2275);
WIRE 16 -1 (-4325 2275)(-4150 2275);
WIRE 16 -1 (-4150 2375)(-4150 2325);
WIRE 16 -1 (-4325 2325)(-4150 2325);
WIRE 16 -1 (-4150 2425)(-4150 2375);
WIRE 16 -1 (-4325 2375)(-4150 2375);
WIRE 16 -1 (-4150 2475)(-4150 2425);
WIRE 16 -1 (-4325 2425)(-4150 2425);
WIRE 16 -1 (-4150 2525)(-4150 2475);
WIRE 16 -1 (-4325 2475)(-4150 2475);
WIRE 16 -1 (-4150 2575)(-4150 2525);
WIRE 16 -1 (-4325 2525)(-4150 2525);
WIRE 16 -1 (-4150 2625)(-4150 2575);
WIRE 16 -1 (-4325 2575)(-4150 2575);
WIRE 16 -1 (-4150 2675)(-4150 2625);
WIRE 16 -1 (-4325 2625)(-4150 2625);
WIRE 16 -1 (-4150 2725)(-4150 2675);
WIRE 16 -1 (-4325 2675)(-4150 2675);
WIRE 16 -1 (-4150 2775)(-4150 2725);
WIRE 16 -1 (-4325 2725)(-4150 2725);
WIRE 16 -1 (-4150 2825)(-4150 2775);
WIRE 16 -1 (-4325 2775)(-4150 2775);
WIRE 16 -1 (-4150 2875)(-4150 2825);
WIRE 16 -1 (-4325 2825)(-4150 2825);
WIRE 16 -1 (-4150 2925)(-4150 2875);
WIRE 16 -1 (-4325 2875)(-4150 2875);
WIRE 16 -1 (-4150 2975)(-4150 2925);
WIRE 16 -1 (-4325 2925)(-4150 2925);
WIRE 16 -1 (-4150 3025)(-4150 2975);
WIRE 16 -1 (-4325 2975)(-4150 2975);
WIRE 16 -1 (-4150 3075)(-4150 3025);
WIRE 16 -1 (-4325 3025)(-4150 3025);
WIRE 16 -1 (-4150 3125)(-4150 3075);
WIRE 16 -1 (-4325 3075)(-4150 3075);
WIRE 16 -1 (-4150 3175)(-4150 3125);
WIRE 16 -1 (-4325 3125)(-4150 3125);
WIRE 16 -1 (-4150 3225)(-4150 3175);
WIRE 16 -1 (-4325 3175)(-4150 3175);
WIRE 16 -1 (-4150 3275)(-4150 3225);
WIRE 16 -1 (-4325 3225)(-4150 3225);
WIRE 16 -1 (-4150 3325)(-4150 3275);
WIRE 16 -1 (-4325 3275)(-4150 3275);
WIRE 16 -1 (-4150 3375)(-4150 3325);
WIRE 16 -1 (-4325 3325)(-4150 3325);
WIRE 16 -1 (-4150 3425)(-4150 3375);
WIRE 16 -1 (-4325 3375)(-4150 3375);
WIRE 16 -1 (-4150 3475)(-4150 3425);
WIRE 16 -1 (-4325 3425)(-4150 3425);
WIRE 16 -1 (-4150 3525)(-4150 3475);
WIRE 16 -1 (-4325 3475)(-4150 3475);
WIRE 16 -1 (-4150 3575)(-4150 3525);
WIRE 16 -1 (-4325 3525)(-4150 3525);
WIRE 16 -1 (-4150 3625)(-4150 3575);
WIRE 16 -1 (-4325 3575)(-4150 3575);
WIRE 16 -1 (-4150 3675)(-4150 3625);
WIRE 16 -1 (-4325 3625)(-4150 3625);
WIRE 16 -1 (-4150 3725)(-4150 3675);
WIRE 16 -1 (-4325 3675)(-4150 3675);
WIRE 16 -1 (-4150 3775)(-4150 3725);
WIRE 16 -1 (-4325 3725)(-4150 3725);
WIRE 16 -1 (-4150 3825)(-4150 3775);
WIRE 16 -1 (-4325 3775)(-4150 3775);
WIRE 16 -1 (-4150 3875)(-4150 3825);
WIRE 16 -1 (-4325 3825)(-4150 3825);
WIRE 16 -1 (-4150 3925)(-4150 3875);
WIRE 16 -1 (-4325 3875)(-4150 3875);
WIRE 16 -1 (-4150 3975)(-4150 3925);
WIRE 16 -1 (-4325 3925)(-4150 3925);
WIRE 16 -1 (-4150 4025)(-4150 3975);
WIRE 16 -1 (-4325 3975)(-4150 3975);
WIRE 16 -1 (-4150 4075)(-4150 4025);
WIRE 16 -1 (-4325 4025)(-4150 4025);
WIRE 16 -1 (-4150 4125)(-4150 4075);
WIRE 16 -1 (-4325 4075)(-4150 4075);
WIRE 16 -1 (-4150 4175)(-4150 4125);
WIRE 16 -1 (-4325 4125)(-4150 4125);
WIRE 16 -1 (-4150 4225)(-4150 4175);
WIRE 16 -1 (-4325 4175)(-4150 4175);
WIRE 16 -1 (-4150 4275)(-4150 4225);
WIRE 16 -1 (-4325 4225)(-4150 4225);
WIRE 16 -1 (-4150 4325)(-4150 4275);
WIRE 16 -1 (-4325 4275)(-4150 4275);
WIRE 16 -1 (-4150 4375)(-4150 4325);
WIRE 16 -1 (-4325 4325)(-4150 4325);
WIRE 16 -1 (-4150 4425)(-4150 4375);
WIRE 16 -1 (-4325 4375)(-4150 4375);
WIRE 16 -1 (-4150 4475)(-4150 4425);
WIRE 16 -1 (-4325 4425)(-4150 4425);
WIRE 16 -1 (-4150 4525)(-4150 4475);
WIRE 16 -1 (-4325 4475)(-4150 4475);
WIRE 16 -1 (-4325 4525)(-4150 4525);
WIRE 16 -1 (-5950 575)(-5950 450);
WIRE 16 -1 (-5950 625)(-5950 575);
WIRE 16 -1 (-6125 575)(-5950 575);
WIRE 16 -1 (-5950 675)(-5950 625);
WIRE 16 -1 (-6125 625)(-5950 625);
WIRE 16 -1 (-5950 725)(-5950 675);
WIRE 16 -1 (-6125 675)(-5950 675);
WIRE 16 -1 (-5950 775)(-5950 725);
WIRE 16 -1 (-6125 725)(-5950 725);
WIRE 16 -1 (-5950 825)(-5950 775);
WIRE 16 -1 (-6125 775)(-5950 775);
WIRE 16 -1 (-5950 875)(-5950 825);
WIRE 16 -1 (-6125 825)(-5950 825);
WIRE 16 -1 (-5950 925)(-5950 875);
WIRE 16 -1 (-6125 875)(-5950 875);
WIRE 16 -1 (-5950 975)(-5950 925);
WIRE 16 -1 (-6125 925)(-5950 925);
WIRE 16 -1 (-5950 1025)(-5950 975);
WIRE 16 -1 (-6125 975)(-5950 975);
WIRE 16 -1 (-5950 1075)(-5950 1025);
WIRE 16 -1 (-6125 1025)(-5950 1025);
WIRE 16 -1 (-5950 1125)(-5950 1075);
WIRE 16 -1 (-6125 1075)(-5950 1075);
WIRE 16 -1 (-5950 1175)(-5950 1125);
WIRE 16 -1 (-6125 1125)(-5950 1125);
WIRE 16 -1 (-5950 1225)(-5950 1175);
WIRE 16 -1 (-6125 1175)(-5950 1175);
WIRE 16 -1 (-5950 1275)(-5950 1225);
WIRE 16 -1 (-6125 1225)(-5950 1225);
WIRE 16 -1 (-5950 1325)(-5950 1275);
WIRE 16 -1 (-6125 1275)(-5950 1275);
WIRE 16 -1 (-5950 1375)(-5950 1325);
WIRE 16 -1 (-6125 1325)(-5950 1325);
WIRE 16 -1 (-5950 1425)(-5950 1375);
WIRE 16 -1 (-6125 1375)(-5950 1375);
WIRE 16 -1 (-5950 1475)(-5950 1425);
WIRE 16 -1 (-6125 1425)(-5950 1425);
WIRE 16 -1 (-5950 1525)(-5950 1475);
WIRE 16 -1 (-6125 1475)(-5950 1475);
WIRE 16 -1 (-5950 1575)(-5950 1525);
WIRE 16 -1 (-6125 1525)(-5950 1525);
WIRE 16 -1 (-5950 1625)(-5950 1575);
WIRE 16 -1 (-6125 1575)(-5950 1575);
WIRE 16 -1 (-5950 1675)(-5950 1625);
WIRE 16 -1 (-6125 1625)(-5950 1625);
WIRE 16 -1 (-5950 1725)(-5950 1675);
WIRE 16 -1 (-6125 1675)(-5950 1675);
WIRE 16 -1 (-5950 1775)(-5950 1725);
WIRE 16 -1 (-6125 1725)(-5950 1725);
WIRE 16 -1 (-5950 1825)(-5950 1775);
WIRE 16 -1 (-6125 1775)(-5950 1775);
WIRE 16 -1 (-5950 1875)(-5950 1825);
WIRE 16 -1 (-6125 1825)(-5950 1825);
WIRE 16 -1 (-5950 1925)(-5950 1875);
WIRE 16 -1 (-6125 1875)(-5950 1875);
WIRE 16 -1 (-5950 1975)(-5950 1925);
WIRE 16 -1 (-6125 1925)(-5950 1925);
WIRE 16 -1 (-5950 2025)(-5950 1975);
WIRE 16 -1 (-6125 1975)(-5950 1975);
WIRE 16 -1 (-5950 2075)(-5950 2025);
WIRE 16 -1 (-6125 2025)(-5950 2025);
WIRE 16 -1 (-5950 2125)(-5950 2075);
WIRE 16 -1 (-6125 2075)(-5950 2075);
WIRE 16 -1 (-5950 2175)(-5950 2125);
WIRE 16 -1 (-6125 2125)(-5950 2125);
WIRE 16 -1 (-5950 2225)(-5950 2175);
WIRE 16 -1 (-6125 2175)(-5950 2175);
WIRE 16 -1 (-5950 2275)(-5950 2225);
WIRE 16 -1 (-6125 2225)(-5950 2225);
WIRE 16 -1 (-5950 2325)(-5950 2275);
WIRE 16 -1 (-6125 2275)(-5950 2275);
WIRE 16 -1 (-5950 2375)(-5950 2325);
WIRE 16 -1 (-6125 2325)(-5950 2325);
WIRE 16 -1 (-5950 2425)(-5950 2375);
WIRE 16 -1 (-6125 2375)(-5950 2375);
WIRE 16 -1 (-5950 2475)(-5950 2425);
WIRE 16 -1 (-6125 2425)(-5950 2425);
WIRE 16 -1 (-5950 2525)(-5950 2475);
WIRE 16 -1 (-6125 2475)(-5950 2475);
WIRE 16 -1 (-5950 2575)(-5950 2525);
WIRE 16 -1 (-6125 2525)(-5950 2525);
WIRE 16 -1 (-5950 2625)(-5950 2575);
WIRE 16 -1 (-6125 2575)(-5950 2575);
WIRE 16 -1 (-5950 2675)(-5950 2625);
WIRE 16 -1 (-6125 2625)(-5950 2625);
WIRE 16 -1 (-5950 2725)(-5950 2675);
WIRE 16 -1 (-6125 2675)(-5950 2675);
WIRE 16 -1 (-5950 2775)(-5950 2725);
WIRE 16 -1 (-6125 2725)(-5950 2725);
WIRE 16 -1 (-5950 2825)(-5950 2775);
WIRE 16 -1 (-6125 2775)(-5950 2775);
WIRE 16 -1 (-5950 2875)(-5950 2825);
WIRE 16 -1 (-6125 2825)(-5950 2825);
WIRE 16 -1 (-5950 2925)(-5950 2875);
WIRE 16 -1 (-6125 2875)(-5950 2875);
WIRE 16 -1 (-5950 2975)(-5950 2925);
WIRE 16 -1 (-6125 2925)(-5950 2925);
WIRE 16 -1 (-5950 3025)(-5950 2975);
WIRE 16 -1 (-6125 2975)(-5950 2975);
WIRE 16 -1 (-5950 3075)(-5950 3025);
WIRE 16 -1 (-6125 3025)(-5950 3025);
WIRE 16 -1 (-5950 3125)(-5950 3075);
WIRE 16 -1 (-6125 3075)(-5950 3075);
WIRE 16 -1 (-5950 3175)(-5950 3125);
WIRE 16 -1 (-6125 3125)(-5950 3125);
WIRE 16 -1 (-5950 3225)(-5950 3175);
WIRE 16 -1 (-6125 3175)(-5950 3175);
WIRE 16 -1 (-5950 3275)(-5950 3225);
WIRE 16 -1 (-6125 3225)(-5950 3225);
WIRE 16 -1 (-5950 3325)(-5950 3275);
WIRE 16 -1 (-6125 3275)(-5950 3275);
WIRE 16 -1 (-5950 3375)(-5950 3325);
WIRE 16 -1 (-6125 3325)(-5950 3325);
WIRE 16 -1 (-5950 3425)(-5950 3375);
WIRE 16 -1 (-6125 3375)(-5950 3375);
WIRE 16 -1 (-5950 3475)(-5950 3425);
WIRE 16 -1 (-6125 3425)(-5950 3425);
WIRE 16 -1 (-5950 3525)(-5950 3475);
WIRE 16 -1 (-6125 3475)(-5950 3475);
WIRE 16 -1 (-5950 3575)(-5950 3525);
WIRE 16 -1 (-6125 3525)(-5950 3525);
WIRE 16 -1 (-5950 3625)(-5950 3575);
WIRE 16 -1 (-6125 3575)(-5950 3575);
WIRE 16 -1 (-5950 3675)(-5950 3625);
WIRE 16 -1 (-6125 3625)(-5950 3625);
WIRE 16 -1 (-5950 3725)(-5950 3675);
WIRE 16 -1 (-6125 3675)(-5950 3675);
WIRE 16 -1 (-5950 3775)(-5950 3725);
WIRE 16 -1 (-6125 3725)(-5950 3725);
WIRE 16 -1 (-5950 3825)(-5950 3775);
WIRE 16 -1 (-6125 3775)(-5950 3775);
WIRE 16 -1 (-5950 3875)(-5950 3825);
WIRE 16 -1 (-6125 3825)(-5950 3825);
WIRE 16 -1 (-5950 3925)(-5950 3875);
WIRE 16 -1 (-6125 3875)(-5950 3875);
WIRE 16 -1 (-5950 3975)(-5950 3925);
WIRE 16 -1 (-6125 3925)(-5950 3925);
WIRE 16 -1 (-5950 4025)(-5950 3975);
WIRE 16 -1 (-6125 3975)(-5950 3975);
WIRE 16 -1 (-5950 4075)(-5950 4025);
WIRE 16 -1 (-6125 4025)(-5950 4025);
WIRE 16 -1 (-5950 4125)(-5950 4075);
WIRE 16 -1 (-6125 4075)(-5950 4075);
WIRE 16 -1 (-5950 4175)(-5950 4125);
WIRE 16 -1 (-6125 4125)(-5950 4125);
WIRE 16 -1 (-5950 4225)(-5950 4175);
WIRE 16 -1 (-6125 4175)(-5950 4175);
WIRE 16 -1 (-5950 4275)(-5950 4225);
WIRE 16 -1 (-6125 4225)(-5950 4225);
WIRE 16 -1 (-5950 4325)(-5950 4275);
WIRE 16 -1 (-6125 4275)(-5950 4275);
WIRE 16 -1 (-5950 4375)(-5950 4325);
WIRE 16 -1 (-6125 4325)(-5950 4325);
WIRE 16 -1 (-5950 4425)(-5950 4375);
WIRE 16 -1 (-6125 4375)(-5950 4375);
WIRE 16 -1 (-5950 4475)(-5950 4425);
WIRE 16 -1 (-6125 4425)(-5950 4425);
WIRE 16 -1 (-5950 4525)(-5950 4475);
WIRE 16 -1 (-6125 4475)(-5950 4475);
WIRE 16 -1 (-6125 4525)(-5950 4525);
WIRE 16 -1 (-450 1750)(-450 1900);
WIRE 16 -1 (-450 1900)(-450 1950);
WIRE 16 -1 (-625 1900)(-450 1900);
WIRE 16 -1 (-450 2000)(-450 1950);
WIRE 16 -1 (-625 1950)(-450 1950);
WIRE 16 -1 (-450 2050)(-450 2000);
WIRE 16 -1 (-625 2000)(-450 2000);
WIRE 16 -1 (-450 2100)(-450 2050);
WIRE 16 -1 (-625 2050)(-450 2050);
WIRE 16 -1 (-450 2150)(-450 2100);
WIRE 16 -1 (-625 2100)(-450 2100);
WIRE 16 -1 (-450 2200)(-450 2150);
WIRE 16 -1 (-625 2150)(-450 2150);
WIRE 16 -1 (-450 2250)(-450 2200);
WIRE 16 -1 (-625 2200)(-450 2200);
WIRE 16 -1 (-450 2300)(-450 2250);
WIRE 16 -1 (-625 2250)(-450 2250);
WIRE 16 -1 (-450 2350)(-450 2300);
WIRE 16 -1 (-625 2300)(-450 2300);
WIRE 16 -1 (-450 2400)(-450 2350);
WIRE 16 -1 (-625 2350)(-450 2350);
WIRE 16 -1 (-450 2450)(-450 2400);
WIRE 16 -1 (-625 2400)(-450 2400);
WIRE 16 -1 (-450 2500)(-450 2450);
WIRE 16 -1 (-625 2450)(-450 2450);
WIRE 16 -1 (-450 2550)(-450 2500);
WIRE 16 -1 (-625 2500)(-450 2500);
WIRE 16 -1 (-450 2600)(-450 2550);
WIRE 16 -1 (-625 2550)(-450 2550);
WIRE 16 -1 (-450 2650)(-450 2600);
WIRE 16 -1 (-625 2600)(-450 2600);
WIRE 16 -1 (-450 2700)(-450 2650);
WIRE 16 -1 (-625 2650)(-450 2650);
WIRE 16 -1 (-450 2750)(-450 2700);
WIRE 16 -1 (-625 2700)(-450 2700);
WIRE 16 -1 (-450 2800)(-450 2750);
WIRE 16 -1 (-625 2750)(-450 2750);
WIRE 16 -1 (-450 2850)(-450 2800);
WIRE 16 -1 (-625 2800)(-450 2800);
WIRE 16 -1 (-450 2900)(-450 2850);
WIRE 16 -1 (-625 2850)(-450 2850);
WIRE 16 -1 (-450 2950)(-450 2900);
WIRE 16 -1 (-625 2900)(-450 2900);
WIRE 16 -1 (-450 3000)(-450 2950);
WIRE 16 -1 (-625 2950)(-450 2950);
WIRE 16 -1 (-450 3050)(-450 3000);
WIRE 16 -1 (-625 3000)(-450 3000);
WIRE 16 -1 (-450 3100)(-450 3050);
WIRE 16 -1 (-625 3050)(-450 3050);
WIRE 16 -1 (-450 3150)(-450 3100);
WIRE 16 -1 (-625 3100)(-450 3100);
WIRE 16 -1 (-450 3200)(-450 3150);
WIRE 16 -1 (-625 3150)(-450 3150);
WIRE 16 -1 (-450 3250)(-450 3200);
WIRE 16 -1 (-625 3200)(-450 3200);
WIRE 16 -1 (-450 3300)(-450 3250);
WIRE 16 -1 (-625 3250)(-450 3250);
WIRE 16 -1 (-450 3350)(-450 3300);
WIRE 16 -1 (-625 3300)(-450 3300);
WIRE 16 -1 (-450 3400)(-450 3350);
WIRE 16 -1 (-625 3350)(-450 3350);
WIRE 16 -1 (-450 3450)(-450 3400);
WIRE 16 -1 (-625 3400)(-450 3400);
WIRE 16 -1 (-450 3500)(-450 3450);
WIRE 16 -1 (-625 3450)(-450 3450);
WIRE 16 -1 (-450 3550)(-450 3500);
WIRE 16 -1 (-625 3500)(-450 3500);
WIRE 16 -1 (-450 3600)(-450 3550);
WIRE 16 -1 (-625 3550)(-450 3550);
WIRE 16 -1 (-450 3650)(-450 3600);
WIRE 16 -1 (-625 3600)(-450 3600);
WIRE 16 -1 (-450 3700)(-450 3650);
WIRE 16 -1 (-625 3650)(-450 3650);
WIRE 16 -1 (-450 3750)(-450 3700);
WIRE 16 -1 (-625 3700)(-450 3700);
WIRE 16 -1 (-450 3800)(-450 3750);
WIRE 16 -1 (-625 3750)(-450 3750);
WIRE 16 -1 (-450 3850)(-450 3800);
WIRE 16 -1 (-625 3800)(-450 3800);
WIRE 16 -1 (-450 3900)(-450 3850);
WIRE 16 -1 (-625 3850)(-450 3850);
WIRE 16 -1 (-450 3950)(-450 3900);
WIRE 16 -1 (-625 3900)(-450 3900);
WIRE 16 -1 (-450 4000)(-450 3950);
WIRE 16 -1 (-625 3950)(-450 3950);
WIRE 16 -1 (-450 4050)(-450 4000);
WIRE 16 -1 (-625 4000)(-450 4000);
WIRE 16 -1 (-450 4100)(-450 4050);
WIRE 16 -1 (-625 4050)(-450 4050);
WIRE 16 -1 (-450 4150)(-450 4100);
WIRE 16 -1 (-625 4100)(-450 4100);
WIRE 16 -1 (-450 4200)(-450 4150);
WIRE 16 -1 (-625 4150)(-450 4150);
WIRE 16 -1 (-450 4250)(-450 4200);
WIRE 16 -1 (-625 4200)(-450 4200);
WIRE 16 -1 (-450 4300)(-450 4250);
WIRE 16 -1 (-625 4250)(-450 4250);
WIRE 16 -1 (-450 4350)(-450 4300);
WIRE 16 -1 (-625 4300)(-450 4300);
WIRE 16 -1 (-450 4400)(-450 4350);
WIRE 16 -1 (-625 4350)(-450 4350);
WIRE 16 -1 (-450 4450)(-450 4400);
WIRE 16 -1 (-625 4400)(-450 4400);
WIRE 16 -1 (-450 4500)(-450 4450);
WIRE 16 -1 (-625 4450)(-450 4450);
WIRE 16 -1 (-450 4550)(-450 4500);
WIRE 16 -1 (-625 4500)(-450 4500);
WIRE 16 -1 (-625 4550)(-450 4550);
WIRE 16 -1 (-7475 575)(-7475 450);
WIRE 16 -1 (-7475 625)(-7475 575);
WIRE 16 -1 (-7475 575)(-7325 575);
WIRE 16 -1 (-7475 675)(-7475 625);
WIRE 16 -1 (-7325 625)(-7475 625);
WIRE 16 -1 (-7475 725)(-7475 675);
WIRE 16 -1 (-7325 675)(-7475 675);
WIRE 16 -1 (-7475 775)(-7475 725);
WIRE 16 -1 (-7325 725)(-7475 725);
WIRE 16 -1 (-7475 825)(-7475 775);
WIRE 16 -1 (-7325 775)(-7475 775);
WIRE 16 -1 (-7475 875)(-7475 825);
WIRE 16 -1 (-7325 825)(-7475 825);
WIRE 16 -1 (-7475 925)(-7475 875);
WIRE 16 -1 (-7325 875)(-7475 875);
WIRE 16 -1 (-7475 975)(-7475 925);
WIRE 16 -1 (-7325 925)(-7475 925);
WIRE 16 -1 (-7475 1025)(-7475 975);
WIRE 16 -1 (-7325 975)(-7475 975);
WIRE 16 -1 (-7475 1075)(-7475 1025);
WIRE 16 -1 (-7325 1025)(-7475 1025);
WIRE 16 -1 (-7475 1125)(-7475 1075);
WIRE 16 -1 (-7325 1075)(-7475 1075);
WIRE 16 -1 (-7475 1175)(-7475 1125);
WIRE 16 -1 (-7325 1125)(-7475 1125);
WIRE 16 -1 (-7475 1225)(-7475 1175);
WIRE 16 -1 (-7325 1175)(-7475 1175);
WIRE 16 -1 (-7475 1275)(-7475 1225);
WIRE 16 -1 (-7325 1225)(-7475 1225);
WIRE 16 -1 (-7475 1325)(-7475 1275);
WIRE 16 -1 (-7325 1275)(-7475 1275);
WIRE 16 -1 (-7475 1375)(-7475 1325);
WIRE 16 -1 (-7325 1325)(-7475 1325);
WIRE 16 -1 (-7475 1425)(-7475 1375);
WIRE 16 -1 (-7325 1375)(-7475 1375);
WIRE 16 -1 (-7475 1475)(-7475 1425);
WIRE 16 -1 (-7325 1425)(-7475 1425);
WIRE 16 -1 (-7475 1525)(-7475 1475);
WIRE 16 -1 (-7325 1475)(-7475 1475);
WIRE 16 -1 (-7475 1575)(-7475 1525);
WIRE 16 -1 (-7325 1525)(-7475 1525);
WIRE 16 -1 (-7475 1625)(-7475 1575);
WIRE 16 -1 (-7325 1575)(-7475 1575);
WIRE 16 -1 (-7475 1675)(-7475 1625);
WIRE 16 -1 (-7325 1625)(-7475 1625);
WIRE 16 -1 (-7475 1725)(-7475 1675);
WIRE 16 -1 (-7325 1675)(-7475 1675);
WIRE 16 -1 (-7475 1775)(-7475 1725);
WIRE 16 -1 (-7325 1725)(-7475 1725);
WIRE 16 -1 (-7475 1825)(-7475 1775);
WIRE 16 -1 (-7325 1775)(-7475 1775);
WIRE 16 -1 (-7475 1875)(-7475 1825);
WIRE 16 -1 (-7325 1825)(-7475 1825);
WIRE 16 -1 (-7475 1925)(-7475 1875);
WIRE 16 -1 (-7325 1875)(-7475 1875);
WIRE 16 -1 (-7475 1975)(-7475 1925);
WIRE 16 -1 (-7325 1925)(-7475 1925);
WIRE 16 -1 (-7475 2025)(-7475 1975);
WIRE 16 -1 (-7325 1975)(-7475 1975);
WIRE 16 -1 (-7475 2075)(-7475 2025);
WIRE 16 -1 (-7325 2025)(-7475 2025);
WIRE 16 -1 (-7475 2125)(-7475 2075);
WIRE 16 -1 (-7325 2075)(-7475 2075);
WIRE 16 -1 (-7475 2175)(-7475 2125);
WIRE 16 -1 (-7325 2125)(-7475 2125);
WIRE 16 -1 (-7475 2225)(-7475 2175);
WIRE 16 -1 (-7325 2175)(-7475 2175);
WIRE 16 -1 (-7475 2275)(-7475 2225);
WIRE 16 -1 (-7325 2225)(-7475 2225);
WIRE 16 -1 (-7475 2325)(-7475 2275);
WIRE 16 -1 (-7325 2275)(-7475 2275);
WIRE 16 -1 (-7475 2375)(-7475 2325);
WIRE 16 -1 (-7325 2325)(-7475 2325);
WIRE 16 -1 (-7475 2425)(-7475 2375);
WIRE 16 -1 (-7325 2375)(-7475 2375);
WIRE 16 -1 (-7475 2475)(-7475 2425);
WIRE 16 -1 (-7325 2425)(-7475 2425);
WIRE 16 -1 (-7475 2525)(-7475 2475);
WIRE 16 -1 (-7325 2475)(-7475 2475);
WIRE 16 -1 (-7475 2575)(-7475 2525);
WIRE 16 -1 (-7325 2525)(-7475 2525);
WIRE 16 -1 (-7475 2625)(-7475 2575);
WIRE 16 -1 (-7325 2575)(-7475 2575);
WIRE 16 -1 (-7475 2675)(-7475 2625);
WIRE 16 -1 (-7325 2625)(-7475 2625);
WIRE 16 -1 (-7475 2725)(-7475 2675);
WIRE 16 -1 (-7325 2675)(-7475 2675);
WIRE 16 -1 (-7475 2775)(-7475 2725);
WIRE 16 -1 (-7325 2725)(-7475 2725);
WIRE 16 -1 (-7475 2825)(-7475 2775);
WIRE 16 -1 (-7325 2775)(-7475 2775);
WIRE 16 -1 (-7475 2875)(-7475 2825);
WIRE 16 -1 (-7325 2825)(-7475 2825);
WIRE 16 -1 (-7475 2925)(-7475 2875);
WIRE 16 -1 (-7325 2875)(-7475 2875);
WIRE 16 -1 (-7475 2975)(-7475 2925);
WIRE 16 -1 (-7325 2925)(-7475 2925);
WIRE 16 -1 (-7475 3025)(-7475 2975);
WIRE 16 -1 (-7325 2975)(-7475 2975);
WIRE 16 -1 (-7475 3075)(-7475 3025);
WIRE 16 -1 (-7325 3025)(-7475 3025);
WIRE 16 -1 (-7475 3125)(-7475 3075);
WIRE 16 -1 (-7325 3075)(-7475 3075);
WIRE 16 -1 (-7475 3175)(-7475 3125);
WIRE 16 -1 (-7325 3125)(-7475 3125);
WIRE 16 -1 (-7475 3225)(-7475 3175);
WIRE 16 -1 (-7325 3175)(-7475 3175);
WIRE 16 -1 (-7475 3275)(-7475 3225);
WIRE 16 -1 (-7325 3225)(-7475 3225);
WIRE 16 -1 (-7475 3325)(-7475 3275);
WIRE 16 -1 (-7325 3275)(-7475 3275);
WIRE 16 -1 (-7475 3375)(-7475 3325);
WIRE 16 -1 (-7325 3325)(-7475 3325);
WIRE 16 -1 (-7475 3425)(-7475 3375);
WIRE 16 -1 (-7325 3375)(-7475 3375);
WIRE 16 -1 (-7475 3475)(-7475 3425);
WIRE 16 -1 (-7325 3425)(-7475 3425);
WIRE 16 -1 (-7475 3525)(-7475 3475);
WIRE 16 -1 (-7325 3475)(-7475 3475);
WIRE 16 -1 (-7475 3575)(-7475 3525);
WIRE 16 -1 (-7325 3525)(-7475 3525);
WIRE 16 -1 (-7475 3625)(-7475 3575);
WIRE 16 -1 (-7325 3575)(-7475 3575);
WIRE 16 -1 (-7475 3675)(-7475 3625);
WIRE 16 -1 (-7325 3625)(-7475 3625);
WIRE 16 -1 (-7475 3725)(-7475 3675);
WIRE 16 -1 (-7325 3675)(-7475 3675);
WIRE 16 -1 (-7475 3775)(-7475 3725);
WIRE 16 -1 (-7325 3725)(-7475 3725);
WIRE 16 -1 (-7475 3825)(-7475 3775);
WIRE 16 -1 (-7325 3775)(-7475 3775);
WIRE 16 -1 (-7475 3875)(-7475 3825);
WIRE 16 -1 (-7325 3825)(-7475 3825);
WIRE 16 -1 (-7475 3925)(-7475 3875);
WIRE 16 -1 (-7325 3875)(-7475 3875);
WIRE 16 -1 (-7475 3975)(-7475 3925);
WIRE 16 -1 (-7325 3925)(-7475 3925);
WIRE 16 -1 (-7475 4025)(-7475 3975);
WIRE 16 -1 (-7325 3975)(-7475 3975);
WIRE 16 -1 (-7475 4075)(-7475 4025);
WIRE 16 -1 (-7325 4025)(-7475 4025);
WIRE 16 -1 (-7475 4125)(-7475 4075);
WIRE 16 -1 (-7325 4075)(-7475 4075);
WIRE 16 -1 (-7475 4175)(-7475 4125);
WIRE 16 -1 (-7325 4125)(-7475 4125);
WIRE 16 -1 (-7475 4225)(-7475 4175);
WIRE 16 -1 (-7325 4175)(-7475 4175);
WIRE 16 -1 (-7475 4275)(-7475 4225);
WIRE 16 -1 (-7325 4225)(-7475 4225);
WIRE 16 -1 (-7475 4325)(-7475 4275);
WIRE 16 -1 (-7325 4275)(-7475 4275);
WIRE 16 -1 (-7475 4375)(-7475 4325);
WIRE 16 -1 (-7325 4325)(-7475 4325);
WIRE 16 -1 (-7475 4425)(-7475 4375);
WIRE 16 -1 (-7325 4375)(-7475 4375);
WIRE 16 -1 (-7475 4475)(-7475 4425);
WIRE 16 -1 (-7325 4425)(-7475 4425);
WIRE 16 -1 (-7475 4525)(-7475 4475);
WIRE 16 -1 (-7325 4475)(-7475 4475);
WIRE 16 -1 (-7475 4525)(-7325 4525);
DOT 1 (-7475 4275);
DOT 1 (-450 3350);
DOT 1 (-1975 600);
DOT 1 (-5950 3825);
DOT 1 (-5950 1325);
DOT 1 (-4150 3775);
DOT 1 (-2275 4375);
DOT 1 (-1975 4000);
DOT 1 (-450 2650);
DOT 1 (-450 4500);
DOT 1 (-450 4450);
DOT 1 (-450 4400);
DOT 1 (-450 4350);
DOT 1 (-450 4300);
DOT 1 (-450 4250);
DOT 1 (-450 4200);
DOT 1 (-450 4150);
DOT 1 (-450 4100);
DOT 1 (-450 4050);
DOT 1 (-450 4000);
DOT 1 (-450 3950);
DOT 1 (-450 3900);
DOT 1 (-450 3850);
DOT 1 (-450 3800);
DOT 1 (-450 3750);
DOT 1 (-450 3700);
DOT 1 (-450 3650);
DOT 1 (-450 3600);
DOT 1 (-450 3550);
DOT 1 (-450 3500);
DOT 1 (-450 3450);
DOT 1 (-450 3400);
DOT 1 (-450 3300);
DOT 1 (-450 3250);
DOT 1 (-450 3200);
DOT 1 (-450 3150);
DOT 1 (-450 3100);
DOT 1 (-450 3050);
DOT 1 (-450 3000);
DOT 1 (-450 2950);
DOT 1 (-450 2900);
DOT 1 (-450 2850);
DOT 1 (-450 2800);
DOT 1 (-450 2750);
DOT 1 (-450 2700);
DOT 1 (-450 2600);
DOT 1 (-450 2550);
DOT 1 (-450 2500);
DOT 1 (-450 2450);
DOT 1 (-450 2400);
DOT 1 (-450 2350);
DOT 1 (-450 2150);
DOT 1 (-5675 1125);
DOT 1 (-5675 1175);
DOT 1 (-5675 1725);
DOT 1 (-5675 1675);
DOT 1 (-5950 1175);
DOT 1 (-3775 4075);
DOT 1 (-1975 1700);
DOT 1 (-1975 3850);
DOT 1 (-1975 650);
DOT 1 (-1975 700);
DOT 1 (-1975 750);
DOT 1 (-1975 800);
DOT 1 (-1975 850);
DOT 1 (-1975 900);
DOT 1 (-1975 950);
DOT 1 (-1975 1000);
DOT 1 (-1975 1050);
DOT 1 (-1975 1100);
DOT 1 (-1975 1150);
DOT 1 (-1975 1200);
DOT 1 (-1975 1250);
DOT 1 (-2275 975);
DOT 1 (-1975 1300);
DOT 1 (-1975 1350);
DOT 1 (-1975 1400);
DOT 1 (-1975 1450);
DOT 1 (-1975 1500);
DOT 1 (-1975 1550);
DOT 1 (-1975 1600);
DOT 1 (-1975 1650);
DOT 1 (-1975 1750);
DOT 1 (-1975 1800);
DOT 1 (-1975 1850);
DOT 1 (-1975 1900);
DOT 1 (-1975 1950);
DOT 1 (-1975 2000);
DOT 1 (-1975 2050);
DOT 1 (-1975 2150);
DOT 1 (-1975 2200);
DOT 1 (-1975 2250);
DOT 1 (-1975 2300);
DOT 1 (-1975 2350);
DOT 1 (-1975 2400);
DOT 1 (-1975 2450);
DOT 1 (-1975 2500);
DOT 1 (-1975 2550);
DOT 1 (-1975 2600);
DOT 1 (-1975 2650);
DOT 1 (-1975 2700);
DOT 1 (-1975 2750);
DOT 1 (-1975 2800);
DOT 1 (-1975 2850);
DOT 1 (-1975 2900);
DOT 1 (-1975 2950);
DOT 1 (-1975 3050);
DOT 1 (-1975 3100);
DOT 1 (-1975 3150);
DOT 1 (-1975 3200);
DOT 1 (-1975 3250);
DOT 1 (-1975 3300);
DOT 1 (-1975 3350);
DOT 1 (-1975 3400);
DOT 1 (-1975 3450);
DOT 1 (-1975 3500);
DOT 1 (-1975 3550);
DOT 1 (-1975 3600);
DOT 1 (-1975 3650);
DOT 1 (-1975 3700);
DOT 1 (-1975 3750);
DOT 1 (-1975 3800);
DOT 1 (-1975 3900);
DOT 1 (-1975 3950);
DOT 1 (-1975 4050);
DOT 1 (-1975 4100);
DOT 1 (-1975 4150);
DOT 1 (-1975 4200);
DOT 1 (-1975 4250);
DOT 1 (-1975 4300);
DOT 1 (-1975 4350);
DOT 1 (-1975 4400);
DOT 1 (-1975 4450);
DOT 1 (-1975 4500);
DOT 1 (-7475 575);
DOT 1 (-7475 625);
DOT 1 (-7475 675);
DOT 1 (-7475 725);
DOT 1 (-7475 775);
DOT 1 (-7475 825);
DOT 1 (-7475 875);
DOT 1 (-7475 925);
DOT 1 (-7475 975);
DOT 1 (-7475 1025);
DOT 1 (-7475 1075);
DOT 1 (-7475 1125);
DOT 1 (-7475 1175);
DOT 1 (-7475 1225);
DOT 1 (-7475 1275);
DOT 1 (-7475 1325);
DOT 1 (-7475 1375);
DOT 1 (-7475 1425);
DOT 1 (-7475 1475);
DOT 1 (-7475 1575);
DOT 1 (-7475 1525);
DOT 1 (-7475 1675);
DOT 1 (-7475 1775);
DOT 1 (-7475 1825);
DOT 1 (-7475 1875);
DOT 1 (-7475 1925);
DOT 1 (-7475 1975);
DOT 1 (-7475 2025);
DOT 1 (-7475 2075);
DOT 1 (-7475 2125);
DOT 1 (-7475 2175);
DOT 1 (-7475 2275);
DOT 1 (-7475 2325);
DOT 1 (-7475 2375);
DOT 1 (-7475 2425);
DOT 1 (-7475 2475);
DOT 1 (-7475 2525);
DOT 1 (-7475 2575);
DOT 1 (-7475 2625);
DOT 1 (-7475 2675);
DOT 1 (-7475 2725);
DOT 1 (-7475 2775);
DOT 1 (-7475 2825);
DOT 1 (-7475 2875);
DOT 1 (-7475 2925);
DOT 1 (-7475 2975);
DOT 1 (-7475 3025);
DOT 1 (-7475 3125);
DOT 1 (-7475 3075);
DOT 1 (-7475 3175);
DOT 1 (-7475 3225);
DOT 1 (-7475 3275);
DOT 1 (-7475 3325);
DOT 1 (-7475 3375);
DOT 1 (-7475 3425);
DOT 1 (-7475 3475);
DOT 1 (-7475 3525);
DOT 1 (-7475 3575);
DOT 1 (-7475 3625);
DOT 1 (-7475 3675);
DOT 1 (-7475 3725);
DOT 1 (-7475 3775);
DOT 1 (-7475 3825);
DOT 1 (-7475 3875);
DOT 1 (-7475 3925);
DOT 1 (-7475 3975);
DOT 1 (-7475 4025);
DOT 1 (-7475 4075);
DOT 1 (-7475 4125);
DOT 1 (-7475 4175);
DOT 1 (-7475 4225);
DOT 1 (-7475 4325);
DOT 1 (-7475 4375);
DOT 1 (-7475 4425);
DOT 1 (-7475 4475);
DOT 1 (-7475 1725);
DOT 1 (-7475 2225);
DOT 1 (-5675 575);
DOT 1 (-5675 625);
DOT 1 (-5675 675);
DOT 1 (-5675 725);
DOT 1 (-5675 775);
DOT 1 (-5675 825);
DOT 1 (-5675 875);
DOT 1 (-5675 925);
DOT 1 (-5675 975);
DOT 1 (-5675 1025);
DOT 1 (-5675 1075);
DOT 1 (-5675 1225);
DOT 1 (-5675 1275);
DOT 1 (-5675 1325);
DOT 1 (-5675 1375);
DOT 1 (-5675 1425);
DOT 1 (-5675 1475);
DOT 1 (-5675 1525);
DOT 1 (-5675 1625);
DOT 1 (-5675 1825);
DOT 1 (-5675 1925);
DOT 1 (-5675 1975);
DOT 1 (-5675 2075);
DOT 1 (-5675 2125);
DOT 1 (-5675 2175);
DOT 1 (-5675 2225);
DOT 1 (-5675 2275);
DOT 1 (-5675 2325);
DOT 1 (-5675 2375);
DOT 1 (-5675 2425);
DOT 1 (-5675 2475);
DOT 1 (-5675 2525);
DOT 1 (-5675 2575);
DOT 1 (-5675 2625);
DOT 1 (-5675 2675);
DOT 1 (-5675 2725);
DOT 1 (-5675 2775);
DOT 1 (-5675 2825);
DOT 1 (-5675 2875);
DOT 1 (-5675 2925);
DOT 1 (-5675 2975);
DOT 1 (-5675 3025);
DOT 1 (-5675 3125);
DOT 1 (-5675 3175);
DOT 1 (-5675 3225);
DOT 1 (-5675 3275);
DOT 1 (-5675 3325);
DOT 1 (-5675 3375);
DOT 1 (-5675 3425);
DOT 1 (-5675 3475);
DOT 1 (-5675 3525);
DOT 1 (-5675 3575);
DOT 1 (-5675 3625);
DOT 1 (-5675 3725);
DOT 1 (-5675 3775);
DOT 1 (-5675 3825);
DOT 1 (-5675 3875);
DOT 1 (-5675 3925);
DOT 1 (-5675 3975);
DOT 1 (-5675 4025);
DOT 1 (-5675 4075);
DOT 1 (-5675 4125);
DOT 1 (-5675 4175);
DOT 1 (-5675 4225);
DOT 1 (-5675 4275);
DOT 1 (-5675 4325);
DOT 1 (-5675 4375);
DOT 1 (-5675 4425);
DOT 1 (-5675 4475);
DOT 1 (-3775 575);
DOT 1 (-3775 625);
DOT 1 (-3775 675);
DOT 1 (-3775 725);
DOT 1 (-3775 775);
DOT 1 (-3775 825);
DOT 1 (-3775 875);
DOT 1 (-3775 925);
DOT 1 (-3775 975);
DOT 1 (-3775 1025);
DOT 1 (-3775 1075);
DOT 1 (-3775 1125);
DOT 1 (-3775 1175);
DOT 1 (-3775 1225);
DOT 1 (-3775 1275);
DOT 1 (-3775 1325);
DOT 1 (-3775 1375);
DOT 1 (-3775 1425);
DOT 1 (-3775 1475);
DOT 1 (-3775 1575);
DOT 1 (-3775 1525);
DOT 1 (-3775 1625);
DOT 1 (-3775 1675);
DOT 1 (-3775 1725);
DOT 1 (-3775 1775);
DOT 1 (-3775 1825);
DOT 1 (-3775 1875);
DOT 1 (-3775 1925);
DOT 1 (-3775 1975);
DOT 1 (-3775 2025);
DOT 1 (-3775 2075);
DOT 1 (-3775 2125);
DOT 1 (-3775 2175);
DOT 1 (-3775 2225);
DOT 1 (-3775 2275);
DOT 1 (-3775 2325);
DOT 1 (-3775 2375);
DOT 1 (-3775 2425);
DOT 1 (-3775 2475);
DOT 1 (-3775 2525);
DOT 1 (-3775 2575);
DOT 1 (-3775 2625);
DOT 1 (-3775 2675);
DOT 1 (-3775 2725);
DOT 1 (-3775 2775);
DOT 1 (-3775 2825);
DOT 1 (-3775 2875);
DOT 1 (-3775 2925);
DOT 1 (-3775 2975);
DOT 1 (-3775 3025);
DOT 1 (-3775 3125);
DOT 1 (-3775 3075);
DOT 1 (-3775 3175);
DOT 1 (-3775 3225);
DOT 1 (-3775 3275);
DOT 1 (-3775 3325);
DOT 1 (-3775 3375);
DOT 1 (-3775 3425);
DOT 1 (-3775 3475);
DOT 1 (-3775 3525);
DOT 1 (-3775 3575);
DOT 1 (-3775 3625);
DOT 1 (-3775 3675);
DOT 1 (-3775 3725);
DOT 1 (-3775 3775);
DOT 1 (-3775 3825);
DOT 1 (-3775 3875);
DOT 1 (-3775 3925);
DOT 1 (-3775 3975);
DOT 1 (-3775 4025);
DOT 1 (-3775 4125);
DOT 1 (-3775 4175);
DOT 1 (-3775 4225);
DOT 1 (-3775 4275);
DOT 1 (-3775 4325);
DOT 1 (-3775 4375);
DOT 1 (-3775 4425);
DOT 1 (-3775 4475);
DOT 1 (-2275 4475);
DOT 1 (-2275 4325);
DOT 1 (-2275 4425);
DOT 1 (-2275 4225);
DOT 1 (-2275 4275);
DOT 1 (-2275 4175);
DOT 1 (-2275 4075);
DOT 1 (-2275 4125);
DOT 1 (-2275 3975);
DOT 1 (-2275 4025);
DOT 1 (-2275 3925);
DOT 1 (-2275 3825);
DOT 1 (-2275 3875);
DOT 1 (-2275 3725);
DOT 1 (-2275 3775);
DOT 1 (-2275 3675);
DOT 1 (-2275 3575);
DOT 1 (-2275 3625);
DOT 1 (-2275 3425);
DOT 1 (-2275 3475);
DOT 1 (-2275 3525);
DOT 1 (-2275 3325);
DOT 1 (-2275 3375);
DOT 1 (-2275 3175);
DOT 1 (-2275 3225);
DOT 1 (-2275 3275);
DOT 1 (-2275 3075);
DOT 1 (-2275 3125);
DOT 1 (-2275 3025);
DOT 1 (-2275 2925);
DOT 1 (-2275 2975);
DOT 1 (-2275 2825);
DOT 1 (-2275 2875);
DOT 1 (-2275 2775);
DOT 1 (-2275 2725);
DOT 1 (-2275 2675);
DOT 1 (-2275 2525);
DOT 1 (-2275 2625);
DOT 1 (-2275 2575);
DOT 1 (-2275 2475);
DOT 1 (-2275 2425);
DOT 1 (-2275 2375);
DOT 1 (-2275 2325);
DOT 1 (-2275 2225);
DOT 1 (-2275 2025);
DOT 1 (-2275 2125);
DOT 1 (-2275 2075);
DOT 1 (-2275 1925);
DOT 1 (-2275 1975);
DOT 1 (-2275 1875);
DOT 1 (-2275 1825);
DOT 1 (-2275 1775);
DOT 1 (-2275 1675);
DOT 1 (-2275 1725);
DOT 1 (-2275 1625);
DOT 1 (-2275 1525);
DOT 1 (-2275 1375);
DOT 1 (-2275 1425);
DOT 1 (-2275 1475);
DOT 1 (-2275 1325);
DOT 1 (-2275 1275);
DOT 1 (-2275 1125);
DOT 1 (-2275 1175);
DOT 1 (-2275 1225);
DOT 1 (-2275 1025);
DOT 1 (-2275 1075);
DOT 1 (-2275 875);
DOT 1 (-2275 925);
DOT 1 (-2275 775);
DOT 1 (-2275 825);
DOT 1 (-2275 725);
DOT 1 (-2275 675);
DOT 1 (-2275 625);
DOT 1 (-2275 575);
DOT 1 (-4150 4325);
DOT 1 (-4150 4425);
DOT 1 (-4150 4375);
DOT 1 (-4150 4225);
DOT 1 (-4150 4275);
DOT 1 (-4150 4175);
DOT 1 (-4150 4075);
DOT 1 (-4150 4125);
DOT 1 (-4150 3975);
DOT 1 (-4150 4025);
DOT 1 (-4150 3925);
DOT 1 (-4150 3825);
DOT 1 (-4150 3875);
DOT 1 (-4150 3725);
DOT 1 (-4150 3675);
DOT 1 (-4150 3575);
DOT 1 (-4150 3625);
DOT 1 (-4150 3425);
DOT 1 (-4150 3475);
DOT 1 (-4150 3525);
DOT 1 (-4150 3325);
DOT 1 (-4150 3375);
DOT 1 (-4150 3175);
DOT 1 (-4150 3225);
DOT 1 (-4150 3275);
DOT 1 (-4150 3075);
DOT 1 (-4150 3125);
DOT 1 (-4150 3025);
DOT 1 (-4150 2925);
DOT 1 (-4150 2975);
DOT 1 (-4150 2825);
DOT 1 (-4150 2875);
DOT 1 (-4150 2775);
DOT 1 (-4150 2725);
DOT 1 (-4150 2675);
DOT 1 (-4150 2525);
DOT 1 (-4150 2575);
DOT 1 (-4150 2475);
DOT 1 (-4150 2425);
DOT 1 (-4150 2275);
DOT 1 (-4150 2375);
DOT 1 (-4150 2225);
DOT 1 (-4150 2175);
DOT 1 (-4150 2025);
DOT 1 (-4150 2125);
DOT 1 (-4150 2075);
DOT 1 (-4150 1925);
DOT 1 (-4150 1975);
DOT 1 (-4150 1875);
DOT 1 (-4150 1825);
DOT 1 (-4150 1775);
DOT 1 (-4150 1675);
DOT 1 (-4150 1725);
DOT 1 (-4150 1625);
DOT 1 (-4150 1525);
DOT 1 (-4150 1375);
DOT 1 (-4150 1425);
DOT 1 (-4150 1475);
DOT 1 (-4150 1325);
DOT 1 (-4150 1275);
DOT 1 (-4150 1125);
DOT 1 (-4150 1175);
DOT 1 (-4150 1225);
DOT 1 (-4150 1025);
DOT 1 (-4150 1075);
DOT 1 (-4150 975);
DOT 1 (-4150 875);
DOT 1 (-4150 925);
DOT 1 (-4150 775);
DOT 1 (-4150 825);
DOT 1 (-4150 725);
DOT 1 (-4150 675);
DOT 1 (-4150 625);
DOT 1 (-4150 575);
DOT 1 (-5950 4475);
DOT 1 (-5950 4325);
DOT 1 (-5950 4425);
DOT 1 (-5950 4225);
DOT 1 (-5950 4275);
DOT 1 (-5950 4175);
DOT 1 (-5950 4075);
DOT 1 (-5950 4125);
DOT 1 (-5950 3975);
DOT 1 (-5950 4025);
DOT 1 (-5950 3925);
DOT 1 (-5950 3875);
DOT 1 (-5950 3725);
DOT 1 (-5950 3775);
DOT 1 (-5950 3675);
DOT 1 (-5950 3575);
DOT 1 (-5950 3625);
DOT 1 (-5950 3425);
DOT 1 (-5950 3475);
DOT 1 (-5950 3525);
DOT 1 (-5950 3325);
DOT 1 (-5950 3375);
DOT 1 (-5950 3175);
DOT 1 (-5950 3225);
DOT 1 (-5950 3275);
DOT 1 (-5950 3075);
DOT 1 (-5950 3125);
DOT 1 (-5950 3025);
DOT 1 (-5950 2925);
DOT 1 (-5950 2975);
DOT 1 (-5950 2825);
DOT 1 (-5950 2875);
DOT 1 (-5950 2775);
DOT 1 (-5950 2725);
DOT 1 (-5950 2675);
DOT 1 (-5950 2525);
DOT 1 (-5950 2625);
DOT 1 (-5950 2575);
DOT 1 (-5950 2475);
DOT 1 (-5950 2425);
DOT 1 (-5950 2275);
DOT 1 (-5950 2375);
DOT 1 (-5950 2325);
DOT 1 (-5950 2175);
DOT 1 (-5950 2025);
DOT 1 (-5950 2125);
DOT 1 (-5950 2075);
DOT 1 (-5950 1925);
DOT 1 (-5950 1975);
DOT 1 (-5950 1875);
DOT 1 (-5950 1825);
DOT 1 (-5950 1775);
DOT 1 (-5950 1675);
DOT 1 (-5950 1725);
DOT 1 (-5950 1625);
DOT 1 (-5950 1575);
DOT 1 (-5950 1525);
DOT 1 (-5950 1375);
DOT 1 (-5950 1425);
DOT 1 (-5950 1475);
DOT 1 (-5950 1275);
DOT 1 (-5950 1125);
DOT 1 (-5950 1225);
DOT 1 (-5950 1025);
DOT 1 (-5950 1075);
DOT 1 (-5950 975);
DOT 1 (-5950 875);
DOT 1 (-5950 925);
DOT 1 (-5950 775);
DOT 1 (-5950 825);
DOT 1 (-5950 725);
DOT 1 (-5950 675);
DOT 1 (-5950 625);
DOT 1 (-5950 575);
DOT 1 (-4150 2325);
DOT 1 (-4150 2625);
DOT 1 (-5950 4375);
DOT 1 (-5675 3075);
DOT 1 (-5675 3675);
DOT 1 (-7475 1625);
DOT 1 (-4150 4475);
DOT 1 (-5675 2025);
DOT 1 (-5950 2225);
DOT 1 (-5675 1875);
DOT 1 (-2275 2275);
DOT 1 (-1975 2100);
DOT 1 (-2275 2175);
DOT 1 (-2275 1575);
DOT 1 (-4150 1575);
DOT 1 (-5675 1575);
DOT 1 (-5675 1775);
DOT 1 (-450 2250);
DOT 1 (-450 2200);
DOT 1 (-450 2100);
DOT 1 (-450 2050);
DOT 1 (-450 2000);
DOT 1 (-450 1950);
DOT 1 (-450 1900);
DOT 1 (-450 2300);
DOT 1 (-1975 3000);
QUIT
